FILE_TYPE = MACRO_DRAWING;
SET COLOR_WIRE YELLOW;
SET COLOR_PROP MONO;
SET COLOR_DOT WHITE;
SET COLOR_ARC YELLOW;
SET COLOR_BODY GREEN;
SET COLOR_NOTE MONO;
SET PROP_DISPLAY VALUE;
SET PAGE_NUMBER P124;
FORCEADD GND..1
(225 825);
FORCEPROP 3 LASTPIN (225 875) SIG_NAME GND\g
J 0
(235 885);
DISPLAY 0.659574 (235 885);
PAINT MONO (235 885);
DISPLAY INVISIBLE (235 885);
FORCEPROP 1 LAST VOLTAGE 0.0V
J 0
(180 782);
DISPLAY 0.340426 (180 782);
PAINT SKYBLUE (180 782);
DISPLAY INVISIBLE (180 782);
FORCEPROP 2 LAST CDS_LIB mstr_symbols
J 0
(225 825);
PAINT ORANGE (225 825);
DISPLAY INVISIBLE (225 825);
FORCEPROP 1 LAST SIZE 1B
J 0
(300 775);
DISPLAY 1.170213 (300 775);
PAINT AQUA (300 775);
DISPLAY INVISIBLE (300 775);
FORCEPROP 1 LAST BODY_TYPE PLUMBING
J 0
(180 782);
DISPLAY 0.340426 (180 782);
PAINT GREEN (180 782);
DISPLAY INVISIBLE (180 782);
FORCEPROP 1 LAST PATH I13
J 0
(300 825);
DISPLAY 0.872340 (300 825);
PAINT AQUA (300 825);
DISPLAY INVISIBLE (300 825);
FORCEPROP 1 LAST HDL_POWER GND
J 0
(225 975);
DISPLAY 1.170213 (225 975);
PAINT GREEN (225 975);
DISPLAY INVISIBLE (225 975);
FORCEADD GND..1
(2200 4075);
FORCEPROP 3 LASTPIN (2200 4125) SIG_NAME GND\g
J 0
(2210 4135);
DISPLAY 0.659574 (2210 4135);
PAINT MONO (2210 4135);
DISPLAY INVISIBLE (2210 4135);
FORCEPROP 1 LAST VOLTAGE 0.0V
J 0
(2155 4032);
DISPLAY 0.340426 (2155 4032);
PAINT SKYBLUE (2155 4032);
DISPLAY INVISIBLE (2155 4032);
FORCEPROP 1 LAST SIZE 1B
J 0
(2275 4025);
DISPLAY 1.170213 (2275 4025);
PAINT AQUA (2275 4025);
DISPLAY INVISIBLE (2275 4025);
FORCEPROP 2 LAST CDS_LIB mstr_symbols
J 0
(2200 4075);
PAINT ORANGE (2200 4075);
DISPLAY INVISIBLE (2200 4075);
FORCEPROP 1 LAST BODY_TYPE PLUMBING
J 0
(2155 4032);
DISPLAY 0.340426 (2155 4032);
PAINT GREEN (2155 4032);
DISPLAY INVISIBLE (2155 4032);
FORCEPROP 1 LAST PATH I14
J 0
(2275 4075);
DISPLAY 0.872340 (2275 4075);
PAINT AQUA (2275 4075);
DISPLAY INVISIBLE (2275 4075);
FORCEPROP 1 LAST HDL_POWER GND
J 0
(2200 4225);
DISPLAY 1.170213 (2200 4225);
PAINT GREEN (2200 4225);
DISPLAY INVISIBLE (2200 4225);
FORCEADD LBG_CORE_QAT_EXT_D..14
(1200 2700);
FORCEPROP 1 LAST LOCATION U7C1
J 0
(675 4700);
DISPLAY 0.617021 (675 4700);
PAINT AQUA (675 4700);
FORCEPROP 1 LAST PART_NUMBER H91415-002
J 0
(650 750);
DISPLAY 0.617021 (650 750);
PAINT BLUE (650 750);
FORCEPROP 1 LAST MATERIAL IC
J 0
(650 4600);
DISPLAY 0.617021 (650 4600);
PAINT SKYBLUE (650 4600);
FORCEPROP 2 LASTPIN (1800 4200) $PN CA52
J 0
(1810 4210);
DISPLAY 0.617021 (1810 4210);
PAINT ORANGE (1810 4210);
FORCEPROP 2 LASTPIN (1800 4250) $PN CA50
J 0
(1810 4260);
DISPLAY 0.617021 (1810 4260);
PAINT ORANGE (1810 4260);
FORCEPROP 2 LASTPIN (1800 4300) $PN CA26
J 0
(1810 4310);
DISPLAY 0.617021 (1810 4310);
PAINT ORANGE (1810 4310);
FORCEPROP 2 LASTPIN (1800 4350) $PN CA18
J 0
(1810 4360);
DISPLAY 0.617021 (1810 4360);
PAINT ORANGE (1810 4360);
FORCEPROP 2 LASTPIN (1800 4400) $PN CA15
J 0
(1810 4410);
DISPLAY 0.617021 (1810 4410);
PAINT ORANGE (1810 4410);
FORCEPROP 2 LASTPIN (600 950) $PN BY49
J 2
(590 960);
DISPLAY 0.617021 (590 960);
PAINT ORANGE (590 960);
FORCEPROP 2 LASTPIN (600 1000) $PN BY40
J 2
(590 1010);
DISPLAY 0.617021 (590 1010);
PAINT ORANGE (590 1010);
FORCEPROP 2 LASTPIN (600 1100) $PN BW26
J 2
(590 1110);
DISPLAY 0.617021 (590 1110);
PAINT ORANGE (590 1110);
FORCEPROP 2 LASTPIN (600 1150) $PN BW18
J 2
(590 1160);
DISPLAY 0.617021 (590 1160);
PAINT ORANGE (590 1160);
FORCEPROP 2 LASTPIN (600 1200) $PN BW15
J 2
(590 1210);
DISPLAY 0.617021 (590 1210);
PAINT ORANGE (590 1210);
FORCEPROP 2 LASTPIN (600 1250) $PN BV40
J 2
(590 1260);
DISPLAY 0.617021 (590 1260);
PAINT ORANGE (590 1260);
FORCEPROP 2 LASTPIN (600 1350) $PN BU63
J 2
(590 1360);
DISPLAY 0.617021 (590 1360);
PAINT ORANGE (590 1360);
FORCEPROP 2 LASTPIN (600 1400) $PN BU61
J 2
(590 1410);
DISPLAY 0.617021 (590 1410);
PAINT ORANGE (590 1410);
FORCEPROP 2 LASTPIN (600 1450) $PN BU59
J 2
(590 1460);
DISPLAY 0.617021 (590 1460);
PAINT ORANGE (590 1460);
FORCEPROP 2 LASTPIN (600 1500) $PN BU57
J 2
(590 1510);
DISPLAY 0.617021 (590 1510);
PAINT ORANGE (590 1510);
FORCEPROP 2 LASTPIN (600 1550) $PN BU54
J 2
(590 1560);
DISPLAY 0.617021 (590 1560);
PAINT ORANGE (590 1560);
FORCEPROP 2 LASTPIN (600 1600) $PN BU52
J 2
(590 1610);
DISPLAY 0.617021 (590 1610);
PAINT ORANGE (590 1610);
FORCEPROP 2 LASTPIN (600 1650) $PN BU50
J 2
(590 1660);
DISPLAY 0.617021 (590 1660);
PAINT ORANGE (590 1660);
FORCEPROP 2 LASTPIN (600 1700) $PN BU48
J 2
(590 1710);
DISPLAY 0.617021 (590 1710);
PAINT ORANGE (590 1710);
FORCEPROP 2 LASTPIN (600 1750) $PN BU45
J 2
(590 1760);
DISPLAY 0.617021 (590 1760);
PAINT ORANGE (590 1760);
FORCEPROP 2 LASTPIN (600 1800) $PN BU43
J 2
(590 1810);
DISPLAY 0.617021 (590 1810);
PAINT ORANGE (590 1810);
FORCEPROP 2 LASTPIN (600 1850) $PN BU41
J 2
(590 1860);
DISPLAY 0.617021 (590 1860);
PAINT ORANGE (590 1860);
FORCEPROP 2 LASTPIN (600 1900) $PN BU39
J 2
(590 1910);
DISPLAY 0.617021 (590 1910);
PAINT ORANGE (590 1910);
FORCEPROP 2 LASTPIN (600 1950) $PN BU37
J 2
(590 1960);
DISPLAY 0.617021 (590 1960);
PAINT ORANGE (590 1960);
FORCEPROP 2 LASTPIN (600 2000) $PN BU34
J 2
(590 2010);
DISPLAY 0.617021 (590 2010);
PAINT ORANGE (590 2010);
FORCEPROP 2 LASTPIN (600 2050) $PN BU32
J 2
(590 2060);
DISPLAY 0.617021 (590 2060);
PAINT ORANGE (590 2060);
FORCEPROP 2 LASTPIN (600 2100) $PN BU30
J 2
(590 2110);
DISPLAY 0.617021 (590 2110);
PAINT ORANGE (590 2110);
FORCEPROP 2 LASTPIN (600 2150) $PN BU28
J 2
(590 2160);
DISPLAY 0.617021 (590 2160);
PAINT ORANGE (590 2160);
FORCEPROP 2 LASTPIN (600 2200) $PN BU26
J 2
(590 2210);
DISPLAY 0.617021 (590 2210);
PAINT ORANGE (590 2210);
FORCEPROP 2 LASTPIN (600 2250) $PN BU24
J 2
(590 2260);
DISPLAY 0.617021 (590 2260);
PAINT ORANGE (590 2260);
FORCEPROP 2 LASTPIN (600 2300) $PN BU22
J 2
(590 2310);
DISPLAY 0.617021 (590 2310);
PAINT ORANGE (590 2310);
FORCEPROP 2 LASTPIN (600 2350) $PN BU20
J 2
(590 2360);
DISPLAY 0.617021 (590 2360);
PAINT ORANGE (590 2360);
FORCEPROP 2 LASTPIN (600 2400) $PN BU18
J 2
(590 2410);
DISPLAY 0.617021 (590 2410);
PAINT ORANGE (590 2410);
FORCEPROP 2 LASTPIN (600 2450) $PN BU15
J 2
(590 2460);
DISPLAY 0.617021 (590 2460);
PAINT ORANGE (590 2460);
FORCEPROP 2 LASTPIN (600 2500) $PN BV49
J 2
(590 2510);
DISPLAY 0.617021 (590 2510);
PAINT ORANGE (590 2510);
FORCEPROP 2 LASTPIN (600 2550) $PN BU11
J 2
(590 2560);
DISPLAY 0.617021 (590 2560);
PAINT ORANGE (590 2560);
FORCEPROP 2 LASTPIN (600 2600) $PN BU13
J 2
(590 2610);
DISPLAY 0.617021 (590 2610);
PAINT ORANGE (590 2610);
FORCEPROP 2 LASTPIN (600 2650) $PN BT66
J 2
(590 2660);
DISPLAY 0.617021 (590 2660);
PAINT ORANGE (590 2660);
FORCEPROP 2 LASTPIN (600 2700) $PN BR6
J 2
(590 2710);
DISPLAY 0.617021 (590 2710);
PAINT ORANGE (590 2710);
FORCEPROP 2 LASTPIN (600 2750) $PN BR58
J 2
(590 2760);
DISPLAY 0.617021 (590 2760);
PAINT ORANGE (590 2760);
FORCEPROP 2 LASTPIN (600 2800) $PN BR54
J 2
(590 2810);
DISPLAY 0.617021 (590 2810);
PAINT ORANGE (590 2810);
FORCEPROP 2 LASTPIN (600 2850) $PN BT8
J 2
(590 2860);
DISPLAY 0.617021 (590 2860);
PAINT ORANGE (590 2860);
FORCEPROP 2 LASTPIN (600 2900) $PN BR50
J 2
(590 2910);
DISPLAY 0.617021 (590 2910);
PAINT ORANGE (590 2910);
FORCEPROP 2 LASTPIN (600 2950) $PN BR20
J 2
(590 2960);
DISPLAY 0.617021 (590 2960);
PAINT ORANGE (590 2960);
FORCEPROP 2 LASTPIN (600 3000) $PN BN66
J 2
(590 3010);
DISPLAY 0.617021 (590 3010);
PAINT ORANGE (590 3010);
FORCEPROP 2 LASTPIN (600 3050) $PN BN52
J 2
(590 3060);
DISPLAY 0.617021 (590 3060);
PAINT ORANGE (590 3060);
FORCEPROP 2 LASTPIN (600 3100) $PN BN5
J 2
(590 3110);
DISPLAY 0.617021 (590 3110);
PAINT ORANGE (590 3110);
FORCEPROP 2 LASTPIN (600 3150) $PN BN59
J 2
(590 3160);
DISPLAY 0.617021 (590 3160);
PAINT ORANGE (590 3160);
FORCEPROP 2 LASTPIN (600 3200) $PN BN22
J 2
(590 3210);
DISPLAY 0.617021 (590 3210);
PAINT ORANGE (590 3210);
FORCEPROP 2 LASTPIN (600 3250) $PN BM9
J 2
(590 3260);
DISPLAY 0.617021 (590 3260);
PAINT ORANGE (590 3260);
FORCEPROP 2 LASTPIN (600 3300) $PN BM71
J 2
(590 3310);
DISPLAY 0.617021 (590 3310);
PAINT ORANGE (590 3310);
FORCEPROP 2 LASTPIN (600 3350) $PN BM69
J 2
(590 3360);
DISPLAY 0.617021 (590 3360);
PAINT ORANGE (590 3360);
FORCEPROP 2 LASTPIN (600 3400) $PN BM58
J 2
(590 3410);
DISPLAY 0.617021 (590 3410);
PAINT ORANGE (590 3410);
FORCEPROP 2 LASTPIN (600 3450) $PN BM50
J 2
(590 3460);
DISPLAY 0.617021 (590 3460);
PAINT ORANGE (590 3460);
FORCEPROP 2 LASTPIN (600 3500) $PN BM46
J 2
(590 3510);
DISPLAY 0.617021 (590 3510);
PAINT ORANGE (590 3510);
FORCEPROP 2 LASTPIN (600 3550) $PN BN37
J 2
(590 3560);
DISPLAY 0.617021 (590 3560);
PAINT ORANGE (590 3560);
FORCEPROP 2 LASTPIN (600 3600) $PN BM17
J 2
(590 3610);
DISPLAY 0.617021 (590 3610);
PAINT ORANGE (590 3610);
FORCEPROP 2 LASTPIN (600 3650) $PN BM13
J 2
(590 3660);
DISPLAY 0.617021 (590 3660);
PAINT ORANGE (590 3660);
FORCEPROP 2 LASTPIN (600 3700) $PN BL72
J 2
(590 3710);
DISPLAY 0.617021 (590 3710);
PAINT ORANGE (590 3710);
FORCEPROP 2 LASTPIN (600 3750) $PN BL70
J 2
(590 3760);
DISPLAY 0.617021 (590 3760);
PAINT ORANGE (590 3760);
FORCEPROP 2 LASTPIN (600 3800) $PN BL63
J 2
(590 3810);
DISPLAY 0.617021 (590 3810);
PAINT ORANGE (590 3810);
FORCEPROP 2 LASTPIN (600 3850) $PN BL5
J 2
(590 3860);
DISPLAY 0.617021 (590 3860);
PAINT ORANGE (590 3860);
FORCEPROP 2 LASTPIN (600 3900) $PN BL37
J 2
(590 3910);
DISPLAY 0.617021 (590 3910);
PAINT ORANGE (590 3910);
FORCEPROP 2 LASTPIN (600 3950) $PN BL68
J 2
(590 3960);
DISPLAY 0.617021 (590 3960);
PAINT ORANGE (590 3960);
FORCEPROP 2 LASTPIN (600 4000) $PN BL40
J 2
(590 4010);
DISPLAY 0.617021 (590 4010);
PAINT ORANGE (590 4010);
FORCEPROP 2 LASTPIN (600 4050) $PN BL22
J 2
(590 4060);
DISPLAY 0.617021 (590 4060);
PAINT ORANGE (590 4060);
FORCEPROP 2 LASTPIN (600 4100) $PN BK50
J 2
(590 4110);
DISPLAY 0.617021 (590 4110);
PAINT ORANGE (590 4110);
FORCEPROP 2 LASTPIN (600 4150) $PN BK42
J 2
(590 4160);
DISPLAY 0.617021 (590 4160);
PAINT ORANGE (590 4160);
FORCEPROP 2 LASTPIN (600 4200) $PN BK38
J 2
(590 4210);
DISPLAY 0.617021 (590 4210);
PAINT ORANGE (590 4210);
FORCEPROP 2 LASTPIN (600 4250) $PN BK35
J 2
(590 4260);
DISPLAY 0.617021 (590 4260);
PAINT ORANGE (590 4260);
FORCEPROP 2 LASTPIN (600 4300) $PN BK31
J 2
(590 4310);
DISPLAY 0.617021 (590 4310);
PAINT ORANGE (590 4310);
FORCEPROP 2 LASTPIN (600 4350) $PN BK27
J 2
(590 4360);
DISPLAY 0.617021 (590 4360);
PAINT ORANGE (590 4360);
FORCEPROP 2 LASTPIN (600 4400) $PN BK24
J 2
(590 4410);
DISPLAY 0.617021 (590 4410);
PAINT ORANGE (590 4410);
FORCEPROP 2 LASTPIN (600 1050) $PN BW52
J 2
(590 1060);
DISPLAY 0.617021 (590 1060);
PAINT ORANGE (590 1060);
FORCEPROP 2 LASTPIN (600 1300) $PN BU9
J 2
(590 1310);
DISPLAY 0.617021 (590 1310);
PAINT ORANGE (590 1310);
FORCEPROP 1 LAST PACK_TYPE BGA1
J 0
(650 4700);
PAINT SKYBLUE (650 4700);
DISPLAY INVISIBLE (650 4700);
FORCEPROP 2 LAST SEC_TYPE BGA1
J 0
(675 4750);
DISPLAY 1.021277 (675 4750);
PAINT ORANGE (675 4750);
DISPLAY INVISIBLE (675 4750);
FORCEPROP 2 LAST SEC 14
J 0
(675 4750);
DISPLAY 0.680851 (675 4750);
PAINT MONO (675 4750);
DISPLAY INVISIBLE (675 4750);
FORCEPROP 2 LAST CDS_LIB mstr_u_proc
J 0
(1200 2700);
PAINT ORANGE (1200 2700);
DISPLAY INVISIBLE (1200 2700);
FORCEPROP 0 LAST BOM_COST SB
J 0
(450 4350);
DISPLAY 1.361702 (450 4350);
PAINT ORANGE (450 4350);
DISPLAY INVISIBLE (450 4350);
FORCEPROP 2 LAST CDS_LOCATION U7C1
J 0
(675 4700);
DISPLAY 0.617021 (675 4700);
PAINT AQUA (675 4700);
DISPLAY INVISIBLE (675 4700);
FORCEPROP 1 LAST PATH I15
J 0
(1200 4600);
PAINT GREEN (1200 4600);
DISPLAY INVISIBLE (1200 4600);
FORCEPROP 0 LAST ROOM SB
J 0
(450 4250);
DISPLAY 1.361702 (450 4250);
PAINT ORANGE (450 4250);
DISPLAY INVISIBLE (450 4250);
FORCEADD LBG_CORE_QAT_EXT_D..13
(-1475 2725);
FORCEPROP 1 LAST LOCATION U7C1
J 0
(-1975 4750);
DISPLAY 0.617021 (-1975 4750);
PAINT AQUA (-1975 4750);
FORCEPROP 1 LAST PART_NUMBER H91415-002
J 0
(-2025 775);
DISPLAY 0.617021 (-2025 775);
PAINT BLUE (-2025 775);
FORCEPROP 1 LAST MATERIAL IC
J 0
(-2025 4625);
DISPLAY 0.617021 (-2025 4625);
PAINT SKYBLUE (-2025 4625);
FORCEPROP 2 LASTPIN (-875 975) $PN BJ68
J 0
(-865 985);
DISPLAY 0.617021 (-865 985);
PAINT ORANGE (-865 985);
FORCEPROP 2 LASTPIN (-875 1025) $PN BJ52
J 0
(-865 1035);
DISPLAY 0.617021 (-865 1035);
PAINT ORANGE (-865 1035);
FORCEPROP 2 LASTPIN (-875 1075) $PN BJ33
J 0
(-865 1085);
DISPLAY 0.617021 (-865 1085);
PAINT ORANGE (-865 1085);
FORCEPROP 2 LASTPIN (-875 1125) $PN BJ3
J 0
(-865 1135);
DISPLAY 0.617021 (-865 1135);
PAINT ORANGE (-865 1135);
FORCEPROP 2 LASTPIN (-875 1175) $PN BJ26
J 0
(-865 1185);
DISPLAY 0.617021 (-865 1185);
PAINT ORANGE (-865 1185);
FORCEPROP 2 LASTPIN (-875 1225) $PN BJ18
J 0
(-865 1235);
DISPLAY 0.617021 (-865 1235);
PAINT ORANGE (-865 1235);
FORCEPROP 2 LASTPIN (-875 1275) $PN BJ15
J 0
(-865 1285);
DISPLAY 0.617021 (-865 1285);
PAINT ORANGE (-865 1285);
FORCEPROP 2 LASTPIN (-875 1325) $PN BJ7
J 0
(-865 1335);
DISPLAY 0.617021 (-865 1335);
PAINT ORANGE (-865 1335);
FORCEPROP 2 LASTPIN (-875 1375) $PN BJ5
J 0
(-865 1385);
DISPLAY 0.617021 (-865 1385);
PAINT ORANGE (-865 1385);
FORCEPROP 2 LASTPIN (-875 1425) $PN BJ11
J 0
(-865 1435);
DISPLAY 0.617021 (-865 1435);
PAINT ORANGE (-865 1435);
FORCEPROP 2 LASTPIN (-875 1475) $PN BJ1
J 0
(-865 1485);
DISPLAY 0.617021 (-865 1485);
PAINT ORANGE (-865 1485);
FORCEPROP 2 LASTPIN (-875 1525) $PN BH54
J 0
(-865 1535);
DISPLAY 0.617021 (-865 1535);
PAINT ORANGE (-865 1535);
FORCEPROP 2 LASTPIN (-875 1575) $PN BH46
J 0
(-865 1585);
DISPLAY 0.617021 (-865 1585);
PAINT ORANGE (-865 1585);
FORCEPROP 2 LASTPIN (-875 1625) $PN BH42
J 0
(-865 1635);
DISPLAY 0.617021 (-865 1635);
PAINT ORANGE (-865 1635);
FORCEPROP 2 LASTPIN (-875 1675) $PN BH38
J 0
(-865 1685);
DISPLAY 0.617021 (-865 1685);
PAINT ORANGE (-865 1685);
FORCEPROP 2 LASTPIN (-875 1725) $PN BH27
J 0
(-865 1735);
DISPLAY 0.617021 (-865 1735);
PAINT ORANGE (-865 1735);
FORCEPROP 2 LASTPIN (-875 1775) $PN BG63
J 0
(-865 1785);
DISPLAY 0.617021 (-865 1785);
PAINT ORANGE (-865 1785);
FORCEPROP 2 LASTPIN (-875 1825) $PN BG59
J 0
(-865 1835);
DISPLAY 0.617021 (-865 1835);
PAINT ORANGE (-865 1835);
FORCEPROP 2 LASTPIN (-875 1875) $PN BG48
J 0
(-865 1885);
DISPLAY 0.617021 (-865 1885);
PAINT ORANGE (-865 1885);
FORCEPROP 2 LASTPIN (-875 1925) $PN BG33
J 0
(-865 1935);
DISPLAY 0.617021 (-865 1935);
PAINT ORANGE (-865 1935);
FORCEPROP 2 LASTPIN (-875 1975) $PN BF9
J 0
(-865 1985);
DISPLAY 0.617021 (-865 1985);
PAINT ORANGE (-865 1985);
FORCEPROP 2 LASTPIN (-875 2025) $PN BF68
J 0
(-865 2035);
DISPLAY 0.617021 (-865 2035);
PAINT ORANGE (-865 2035);
FORCEPROP 2 LASTPIN (-875 2075) $PN BF65
J 0
(-865 2085);
DISPLAY 0.617021 (-865 2085);
PAINT ORANGE (-865 2085);
FORCEPROP 2 LASTPIN (-875 2125) $PN BF61
J 0
(-865 2135);
DISPLAY 0.617021 (-865 2135);
PAINT ORANGE (-865 2135);
FORCEPROP 2 LASTPIN (-875 2175) $PN BF58
J 0
(-865 2185);
DISPLAY 0.617021 (-865 2185);
PAINT ORANGE (-865 2185);
FORCEPROP 2 LASTPIN (-875 2225) $PN BF50
J 0
(-865 2235);
DISPLAY 0.617021 (-865 2235);
PAINT ORANGE (-865 2235);
FORCEPROP 2 LASTPIN (-875 2275) $PN BF5
J 0
(-865 2285);
DISPLAY 0.617021 (-865 2285);
PAINT ORANGE (-865 2285);
FORCEPROP 2 LASTPIN (-875 2325) $PN BF42
J 0
(-865 2335);
DISPLAY 0.617021 (-865 2335);
PAINT ORANGE (-865 2335);
FORCEPROP 2 LASTPIN (-875 2375) $PN BF38
J 0
(-865 2385);
DISPLAY 0.617021 (-865 2385);
PAINT ORANGE (-865 2385);
FORCEPROP 2 LASTPIN (-875 2425) $PN BF27
J 0
(-865 2435);
DISPLAY 0.617021 (-865 2435);
PAINT ORANGE (-865 2435);
FORCEPROP 2 LASTPIN (-875 2475) $PN BF24
J 0
(-865 2485);
DISPLAY 0.617021 (-865 2485);
PAINT ORANGE (-865 2485);
FORCEPROP 2 LASTPIN (-875 2525) $PN BF20
J 0
(-865 2535);
DISPLAY 0.617021 (-865 2535);
PAINT ORANGE (-865 2535);
FORCEPROP 2 LASTPIN (-875 2575) $PN BG44
J 0
(-865 2585);
DISPLAY 0.617021 (-865 2585);
PAINT ORANGE (-865 2585);
FORCEPROP 2 LASTPIN (-875 2625) $PN BF54
J 0
(-865 2635);
DISPLAY 0.617021 (-865 2635);
PAINT ORANGE (-865 2635);
FORCEPROP 2 LASTPIN (-875 2675) $PN BF17
J 0
(-865 2685);
DISPLAY 0.617021 (-865 2685);
PAINT ORANGE (-865 2685);
FORCEPROP 2 LASTPIN (-875 2725) $PN BF13
J 0
(-865 2735);
DISPLAY 0.617021 (-865 2735);
PAINT ORANGE (-865 2735);
FORCEPROP 2 LASTPIN (-875 2775) $PN BE66
J 0
(-865 2785);
DISPLAY 0.617021 (-865 2785);
PAINT ORANGE (-865 2785);
FORCEPROP 2 LASTPIN (-875 2825) $PN BE63
J 0
(-865 2835);
DISPLAY 0.617021 (-865 2835);
PAINT ORANGE (-865 2835);
FORCEPROP 2 LASTPIN (-875 2875) $PN BE59
J 0
(-865 2885);
DISPLAY 0.617021 (-865 2885);
PAINT ORANGE (-865 2885);
FORCEPROP 2 LASTPIN (-875 2925) $PN BE56
J 0
(-865 2935);
DISPLAY 0.617021 (-865 2935);
PAINT ORANGE (-865 2935);
FORCEPROP 2 LASTPIN (-875 2975) $PN BE37
J 0
(-865 2985);
DISPLAY 0.617021 (-865 2985);
PAINT ORANGE (-865 2985);
FORCEPROP 2 LASTPIN (-875 3025) $PN BE33
J 0
(-865 3035);
DISPLAY 0.617021 (-865 3035);
PAINT ORANGE (-865 3035);
FORCEPROP 2 LASTPIN (-875 3075) $PN BE29
J 0
(-865 3085);
DISPLAY 0.617021 (-865 3085);
PAINT ORANGE (-865 3085);
FORCEPROP 2 LASTPIN (-875 3125) $PN BD68
J 0
(-865 3135);
DISPLAY 0.617021 (-865 3135);
PAINT ORANGE (-865 3135);
FORCEPROP 2 LASTPIN (-875 3175) $PN BD54
J 0
(-865 3185);
DISPLAY 0.617021 (-865 3185);
PAINT ORANGE (-865 3185);
FORCEPROP 2 LASTPIN (-875 3225) $PN BD50
J 0
(-865 3235);
DISPLAY 0.617021 (-865 3235);
PAINT ORANGE (-865 3235);
FORCEPROP 2 LASTPIN (-875 3275) $PN BD5
J 0
(-865 3285);
DISPLAY 0.617021 (-865 3285);
PAINT ORANGE (-865 3285);
FORCEPROP 2 LASTPIN (-875 3325) $PN BD35
J 0
(-865 3335);
DISPLAY 0.617021 (-865 3335);
PAINT ORANGE (-865 3335);
FORCEPROP 2 LASTPIN (-875 3375) $PN BD31
J 0
(-865 3385);
DISPLAY 0.617021 (-865 3385);
PAINT ORANGE (-865 3385);
FORCEPROP 2 LASTPIN (-875 3425) $PN BD27
J 0
(-865 3435);
DISPLAY 0.617021 (-865 3435);
PAINT ORANGE (-865 3435);
FORCEPROP 2 LASTPIN (-875 3475) $PN BD24
J 0
(-865 3485);
DISPLAY 0.617021 (-865 3485);
PAINT ORANGE (-865 3485);
FORCEPROP 2 LASTPIN (-875 3525) $PN BC71
J 0
(-865 3535);
DISPLAY 0.617021 (-865 3535);
PAINT ORANGE (-865 3535);
FORCEPROP 2 LASTPIN (-875 3575) $PN BC69
J 0
(-865 3585);
DISPLAY 0.617021 (-865 3585);
PAINT ORANGE (-865 3585);
FORCEPROP 2 LASTPIN (-875 3625) $PN BB72
J 0
(-865 3635);
DISPLAY 0.617021 (-865 3635);
PAINT ORANGE (-865 3635);
FORCEPROP 2 LASTPIN (-875 3675) $PN BB70
J 0
(-865 3685);
DISPLAY 0.617021 (-865 3685);
PAINT ORANGE (-865 3685);
FORCEPROP 2 LASTPIN (-875 3725) $PN BB68
J 0
(-865 3735);
DISPLAY 0.617021 (-865 3735);
PAINT ORANGE (-865 3735);
FORCEPROP 2 LASTPIN (-875 3775) $PN BB66
J 0
(-865 3785);
DISPLAY 0.617021 (-865 3785);
PAINT ORANGE (-865 3785);
FORCEPROP 2 LASTPIN (-875 3825) $PN BB59
J 0
(-865 3835);
DISPLAY 0.617021 (-865 3835);
PAINT ORANGE (-865 3835);
FORCEPROP 2 LASTPIN (-875 3875) $PN BB44
J 0
(-865 3885);
DISPLAY 0.617021 (-865 3885);
PAINT ORANGE (-865 3885);
FORCEPROP 2 LASTPIN (-875 3925) $PN BB22
J 0
(-865 3935);
DISPLAY 0.617021 (-865 3935);
PAINT ORANGE (-865 3935);
FORCEPROP 2 LASTPIN (-875 3975) $PN BB18
J 0
(-865 3985);
DISPLAY 0.617021 (-865 3985);
PAINT ORANGE (-865 3985);
FORCEPROP 2 LASTPIN (-875 4025) $PN BB15
J 0
(-865 4035);
DISPLAY 0.617021 (-865 4035);
PAINT ORANGE (-865 4035);
FORCEPROP 2 LASTPIN (-875 4075) $PN BB11
J 0
(-865 4085);
DISPLAY 0.617021 (-865 4085);
PAINT ORANGE (-865 4085);
FORCEPROP 2 LASTPIN (-875 4125) $PN BB7
J 0
(-865 4135);
DISPLAY 0.617021 (-865 4135);
PAINT ORANGE (-865 4135);
FORCEPROP 2 LASTPIN (-875 4175) $PN BB5
J 0
(-865 4185);
DISPLAY 0.617021 (-865 4185);
PAINT ORANGE (-865 4185);
FORCEPROP 2 LASTPIN (-875 4225) $PN BA58
J 0
(-865 4235);
DISPLAY 0.617021 (-865 4235);
PAINT ORANGE (-865 4235);
FORCEPROP 2 LASTPIN (-875 4275) $PN BA54
J 0
(-865 4285);
DISPLAY 0.617021 (-865 4285);
PAINT ORANGE (-865 4285);
FORCEPROP 2 LASTPIN (-875 4325) $PN BA50
J 0
(-865 4335);
DISPLAY 0.617021 (-865 4335);
PAINT ORANGE (-865 4335);
FORCEPROP 2 LASTPIN (-875 4375) $PN AY68
J 0
(-865 4385);
DISPLAY 0.617021 (-865 4385);
PAINT ORANGE (-865 4385);
FORCEPROP 2 LASTPIN (-875 4425) $PN AY63
J 0
(-865 4435);
DISPLAY 0.617021 (-865 4435);
PAINT ORANGE (-865 4435);
FORCEPROP 2 LASTPIN (-2075 975) $PN AY56
J 2
(-2085 985);
DISPLAY 0.617021 (-2085 985);
PAINT ORANGE (-2085 985);
FORCEPROP 2 LASTPIN (-2075 1025) $PN AY22
J 2
(-2085 1035);
DISPLAY 0.617021 (-2085 1035);
PAINT ORANGE (-2085 1035);
FORCEPROP 2 LASTPIN (-2075 1075) $PN AY5
J 2
(-2085 1085);
DISPLAY 0.617021 (-2085 1085);
PAINT ORANGE (-2085 1085);
FORCEPROP 2 LASTPIN (-2075 1125) $PN AW61
J 2
(-2085 1135);
DISPLAY 0.617021 (-2085 1135);
PAINT ORANGE (-2085 1135);
FORCEPROP 2 LASTPIN (-2075 1175) $PN AW58
J 2
(-2085 1185);
DISPLAY 0.617021 (-2085 1185);
PAINT ORANGE (-2085 1185);
FORCEPROP 2 LASTPIN (-2075 1225) $PN AW50
J 2
(-2085 1235);
DISPLAY 0.617021 (-2085 1235);
PAINT ORANGE (-2085 1235);
FORCEPROP 2 LASTPIN (-2075 1275) $PN AW46
J 2
(-2085 1285);
DISPLAY 0.617021 (-2085 1285);
PAINT ORANGE (-2085 1285);
FORCEPROP 2 LASTPIN (-2075 1325) $PN AW41
J 2
(-2085 1335);
DISPLAY 0.617021 (-2085 1335);
PAINT ORANGE (-2085 1335);
FORCEPROP 2 LASTPIN (-2075 1375) $PN AW39
J 2
(-2085 1385);
DISPLAY 0.617021 (-2085 1385);
PAINT ORANGE (-2085 1385);
FORCEPROP 2 LASTPIN (-2075 1425) $PN AW37
J 2
(-2085 1435);
DISPLAY 0.617021 (-2085 1435);
PAINT ORANGE (-2085 1435);
FORCEPROP 2 LASTPIN (-2075 1475) $PN AW36
J 2
(-2085 1485);
DISPLAY 0.617021 (-2085 1485);
PAINT ORANGE (-2085 1485);
FORCEPROP 2 LASTPIN (-2075 1525) $PN AW34
J 2
(-2085 1535);
DISPLAY 0.617021 (-2085 1535);
PAINT ORANGE (-2085 1535);
FORCEPROP 2 LASTPIN (-2075 1575) $PN AW32
J 2
(-2085 1585);
DISPLAY 0.617021 (-2085 1585);
PAINT ORANGE (-2085 1585);
FORCEPROP 2 LASTPIN (-2075 1625) $PN AW30
J 2
(-2085 1635);
DISPLAY 0.617021 (-2085 1635);
PAINT ORANGE (-2085 1635);
FORCEPROP 2 LASTPIN (-2075 1675) $PN AW26
J 2
(-2085 1685);
DISPLAY 0.617021 (-2085 1685);
PAINT ORANGE (-2085 1685);
FORCEPROP 2 LASTPIN (-2075 1725) $PN AW17
J 2
(-2085 1735);
DISPLAY 0.617021 (-2085 1735);
PAINT ORANGE (-2085 1735);
FORCEPROP 2 LASTPIN (-2075 1775) $PN AW13
J 2
(-2085 1785);
DISPLAY 0.617021 (-2085 1785);
PAINT ORANGE (-2085 1785);
FORCEPROP 2 LASTPIN (-2075 1825) $PN AW9
J 2
(-2085 1835);
DISPLAY 0.617021 (-2085 1835);
PAINT ORANGE (-2085 1835);
FORCEPROP 2 LASTPIN (-2075 1875) $PN AV68
J 2
(-2085 1885);
DISPLAY 0.617021 (-2085 1885);
PAINT ORANGE (-2085 1885);
FORCEPROP 2 LASTPIN (-2075 1925) $PN AV59
J 2
(-2085 1935);
DISPLAY 0.617021 (-2085 1935);
PAINT ORANGE (-2085 1935);
FORCEPROP 2 LASTPIN (-2075 1975) $PN AV22
J 2
(-2085 1985);
DISPLAY 0.617021 (-2085 1985);
PAINT ORANGE (-2085 1985);
FORCEPROP 2 LASTPIN (-2075 2025) $PN AV5
J 2
(-2085 2035);
DISPLAY 0.617021 (-2085 2035);
PAINT ORANGE (-2085 2035);
FORCEPROP 2 LASTPIN (-2075 2075) $PN AU61
J 2
(-2085 2085);
DISPLAY 0.617021 (-2085 2085);
PAINT ORANGE (-2085 2085);
FORCEPROP 2 LASTPIN (-2075 2125) $PN AU54
J 2
(-2085 2135);
DISPLAY 0.617021 (-2085 2135);
PAINT ORANGE (-2085 2135);
FORCEPROP 2 LASTPIN (-2075 2175) $PN AU50
J 2
(-2085 2185);
DISPLAY 0.617021 (-2085 2185);
PAINT ORANGE (-2085 2185);
FORCEPROP 2 LASTPIN (-2075 2225) $PN AU46
J 2
(-2085 2235);
DISPLAY 0.617021 (-2085 2235);
PAINT ORANGE (-2085 2235);
FORCEPROP 2 LASTPIN (-2075 2275) $PN AU41
J 2
(-2085 2285);
DISPLAY 0.617021 (-2085 2285);
PAINT ORANGE (-2085 2285);
FORCEPROP 2 LASTPIN (-2075 2325) $PN AE22
J 2
(-2085 2335);
DISPLAY 0.617021 (-2085 2335);
PAINT ORANGE (-2085 2335);
FORCEPROP 2 LASTPIN (-2075 2375) $PN AU30
J 2
(-2085 2385);
DISPLAY 0.617021 (-2085 2385);
PAINT ORANGE (-2085 2385);
FORCEPROP 2 LASTPIN (-2075 2425) $PN AU26
J 2
(-2085 2435);
DISPLAY 0.617021 (-2085 2435);
PAINT ORANGE (-2085 2435);
FORCEPROP 2 LASTPIN (-2075 2475) $PN AT59
J 2
(-2085 2485);
DISPLAY 0.617021 (-2085 2485);
PAINT ORANGE (-2085 2485);
FORCEPROP 2 LASTPIN (-2075 2525) $PN AT46
J 2
(-2085 2535);
DISPLAY 0.617021 (-2085 2535);
PAINT ORANGE (-2085 2535);
FORCEPROP 2 LASTPIN (-2075 2575) $PN AT41
J 2
(-2085 2585);
DISPLAY 0.617021 (-2085 2585);
PAINT ORANGE (-2085 2585);
FORCEPROP 2 LASTPIN (-2075 2625) $PN AT30
J 2
(-2085 2635);
DISPLAY 0.617021 (-2085 2635);
PAINT ORANGE (-2085 2635);
FORCEPROP 2 LASTPIN (-2075 2675) $PN AT26
J 2
(-2085 2685);
DISPLAY 0.617021 (-2085 2685);
PAINT ORANGE (-2085 2685);
FORCEPROP 2 LASTPIN (-2075 2775) $PN AT18
J 2
(-2085 2785);
DISPLAY 0.617021 (-2085 2785);
PAINT ORANGE (-2085 2785);
FORCEPROP 2 LASTPIN (-2075 2825) $PN AT15
J 2
(-2085 2835);
DISPLAY 0.617021 (-2085 2835);
PAINT ORANGE (-2085 2835);
FORCEPROP 2 LASTPIN (-2075 2875) $PN AT11
J 2
(-2085 2885);
DISPLAY 0.617021 (-2085 2885);
PAINT ORANGE (-2085 2885);
FORCEPROP 2 LASTPIN (-2075 2925) $PN AT7
J 2
(-2085 2935);
DISPLAY 0.617021 (-2085 2935);
PAINT ORANGE (-2085 2935);
FORCEPROP 2 LASTPIN (-2075 2975) $PN AR72
J 2
(-2085 2985);
DISPLAY 0.617021 (-2085 2985);
PAINT ORANGE (-2085 2985);
FORCEPROP 2 LASTPIN (-2075 3025) $PN AR70
J 2
(-2085 3035);
DISPLAY 0.617021 (-2085 3035);
PAINT ORANGE (-2085 3035);
FORCEPROP 2 LASTPIN (-2075 3075) $PN AR68
J 2
(-2085 3085);
DISPLAY 0.617021 (-2085 3085);
PAINT ORANGE (-2085 3085);
FORCEPROP 2 LASTPIN (-2075 3125) $PN AR65
J 2
(-2085 3135);
DISPLAY 0.617021 (-2085 3135);
PAINT ORANGE (-2085 3135);
FORCEPROP 2 LASTPIN (-2075 3175) $PN AR58
J 2
(-2085 3185);
DISPLAY 0.617021 (-2085 3185);
PAINT ORANGE (-2085 3185);
FORCEPROP 2 LASTPIN (-2075 3225) $PN AR50
J 2
(-2085 3235);
DISPLAY 0.617021 (-2085 3235);
PAINT ORANGE (-2085 3235);
FORCEPROP 2 LASTPIN (-2075 3275) $PN AR5
J 2
(-2085 3285);
DISPLAY 0.617021 (-2085 3285);
PAINT ORANGE (-2085 3285);
FORCEPROP 2 LASTPIN (-2075 3325) $PN AP66
J 2
(-2085 3335);
DISPLAY 0.617021 (-2085 3335);
PAINT ORANGE (-2085 3335);
FORCEPROP 2 LASTPIN (-2075 3375) $PN AP52
J 2
(-2085 3385);
DISPLAY 0.617021 (-2085 3385);
PAINT ORANGE (-2085 3385);
FORCEPROP 2 LASTPIN (-2075 3425) $PN AP46
J 2
(-2085 3435);
DISPLAY 0.617021 (-2085 3435);
PAINT ORANGE (-2085 3435);
FORCEPROP 2 LASTPIN (-2075 3475) $PN AP41
J 2
(-2085 3485);
DISPLAY 0.617021 (-2085 3485);
PAINT ORANGE (-2085 3485);
FORCEPROP 2 LASTPIN (-2075 3525) $PN AP4
J 2
(-2085 3535);
DISPLAY 0.617021 (-2085 3535);
PAINT ORANGE (-2085 3535);
FORCEPROP 2 LASTPIN (-2075 3575) $PN AP30
J 2
(-2085 3585);
DISPLAY 0.617021 (-2085 3585);
PAINT ORANGE (-2085 3585);
FORCEPROP 2 LASTPIN (-2075 3625) $PN AP26
J 2
(-2085 3635);
DISPLAY 0.617021 (-2085 3635);
PAINT ORANGE (-2085 3635);
FORCEPROP 2 LASTPIN (-2075 3675) $PN AP2
J 2
(-2085 3685);
DISPLAY 0.617021 (-2085 3685);
PAINT ORANGE (-2085 3685);
FORCEPROP 2 LASTPIN (-2075 3725) $PN AN9
J 2
(-2085 3735);
DISPLAY 0.617021 (-2085 3735);
PAINT ORANGE (-2085 3735);
FORCEPROP 2 LASTPIN (-2075 3775) $PN AN58
J 2
(-2085 3785);
DISPLAY 0.617021 (-2085 3785);
PAINT ORANGE (-2085 3785);
FORCEPROP 2 LASTPIN (-2075 3825) $PN AN5
J 2
(-2085 3835);
DISPLAY 0.617021 (-2085 3835);
PAINT ORANGE (-2085 3835);
FORCEPROP 2 LASTPIN (-2075 3925) $PN AP22
J 2
(-2085 3935);
DISPLAY 0.617021 (-2085 3935);
PAINT ORANGE (-2085 3935);
FORCEPROP 2 LASTPIN (-2075 3975) $PN AN68
J 2
(-2085 3985);
DISPLAY 0.617021 (-2085 3985);
PAINT ORANGE (-2085 3985);
FORCEPROP 2 LASTPIN (-2075 4075) $PN AN13
J 2
(-2085 4085);
DISPLAY 0.617021 (-2085 4085);
PAINT ORANGE (-2085 4085);
FORCEPROP 2 LASTPIN (-2075 4125) $PN AM46
J 2
(-2085 4135);
DISPLAY 0.617021 (-2085 4135);
PAINT ORANGE (-2085 4135);
FORCEPROP 2 LASTPIN (-2075 4175) $PN AM41
J 2
(-2085 4185);
DISPLAY 0.617021 (-2085 4185);
PAINT ORANGE (-2085 4185);
FORCEPROP 2 LASTPIN (-2075 4225) $PN AM30
J 2
(-2085 4235);
DISPLAY 0.617021 (-2085 4235);
PAINT ORANGE (-2085 4235);
FORCEPROP 2 LASTPIN (-2075 4275) $PN AM26
J 2
(-2085 4285);
DISPLAY 0.617021 (-2085 4285);
PAINT ORANGE (-2085 4285);
FORCEPROP 2 LASTPIN (-2075 4325) $PN AL72
J 2
(-2085 4335);
DISPLAY 0.617021 (-2085 4335);
PAINT ORANGE (-2085 4335);
FORCEPROP 2 LASTPIN (-2075 4375) $PN AL70
J 2
(-2085 4385);
DISPLAY 0.617021 (-2085 4385);
PAINT ORANGE (-2085 4385);
FORCEPROP 2 LASTPIN (-2075 4425) $PN AL68
J 2
(-2085 4435);
DISPLAY 0.617021 (-2085 4435);
PAINT ORANGE (-2085 4435);
FORCEPROP 2 LASTPIN (-2075 4025) $PN AN17
J 2
(-2085 4035);
DISPLAY 0.617021 (-2085 4035);
PAINT ORANGE (-2085 4035);
FORCEPROP 2 LASTPIN (-2075 3875) $PN AN20
J 2
(-2085 3885);
DISPLAY 0.617021 (-2085 3885);
PAINT ORANGE (-2085 3885);
FORCEPROP 2 LASTPIN (-2075 2725) $PN AT22
J 2
(-2085 2735);
DISPLAY 0.617021 (-2085 2735);
PAINT ORANGE (-2085 2735);
FORCEPROP 1 LAST PACK_TYPE BGA1
J 0
(-2025 4725);
PAINT SKYBLUE (-2025 4725);
DISPLAY INVISIBLE (-2025 4725);
FORCEPROP 2 LAST SEC_TYPE BGA1
J 0
(-1975 4800);
DISPLAY 1.021277 (-1975 4800);
PAINT ORANGE (-1975 4800);
DISPLAY INVISIBLE (-1975 4800);
FORCEPROP 2 LAST SEC 13
J 0
(-1975 4800);
DISPLAY 0.680851 (-1975 4800);
PAINT MONO (-1975 4800);
DISPLAY INVISIBLE (-1975 4800);
FORCEPROP 2 LAST CDS_LIB mstr_u_proc
J 0
(-1475 2725);
PAINT ORANGE (-1475 2725);
DISPLAY INVISIBLE (-1475 2725);
FORCEPROP 0 LAST BOM_COST SB
J 0
(-2225 4375);
DISPLAY 1.361702 (-2225 4375);
PAINT ORANGE (-2225 4375);
DISPLAY INVISIBLE (-2225 4375);
FORCEPROP 2 LAST CDS_LOCATION U7C1
J 0
(-1975 4750);
DISPLAY 0.617021 (-1975 4750);
PAINT AQUA (-1975 4750);
DISPLAY INVISIBLE (-1975 4750);
FORCEPROP 1 LAST PATH I16
J 0
(-1475 4625);
PAINT GREEN (-1475 4625);
DISPLAY INVISIBLE (-1475 4625);
FORCEPROP 0 LAST ROOM SB
J 0
(-2225 4275);
DISPLAY 1.361702 (-2225 4275);
PAINT ORANGE (-2225 4275);
DISPLAY INVISIBLE (-2225 4275);
FORCEADD LBG_CORE_QAT_EXT_D..12
(-4000 2700);
FORCEPROP 2 LASTPIN (-3400 1600) $PN AJ68
J 0
(-3390 1610);
DISPLAY 0.617021 (-3390 1610);
PAINT ORANGE (-3390 1610);
FORCEPROP 1 LAST PART_NUMBER H91415-002
J 0
(-4550 750);
DISPLAY 0.617021 (-4550 750);
PAINT BLUE (-4550 750);
FORCEPROP 1 LAST MATERIAL IC
J 0
(-4550 4600);
DISPLAY 0.617021 (-4550 4600);
PAINT SKYBLUE (-4550 4600);
FORCEPROP 2 LASTPIN (-3400 950) $PN AL59
J 0
(-3390 960);
DISPLAY 0.617021 (-3390 960);
PAINT ORANGE (-3390 960);
FORCEPROP 2 LASTPIN (-3400 1000) $PN AL52
J 0
(-3390 1010);
DISPLAY 0.617021 (-3390 1010);
PAINT ORANGE (-3390 1010);
FORCEPROP 2 LASTPIN (-3400 1050) $PN AL5
J 0
(-3390 1060);
DISPLAY 0.617021 (-3390 1060);
PAINT ORANGE (-3390 1060);
FORCEPROP 2 LASTPIN (-3400 1100) $PN AL22
J 0
(-3390 1110);
DISPLAY 0.617021 (-3390 1110);
PAINT ORANGE (-3390 1110);
FORCEPROP 2 LASTPIN (-3400 1150) $PN AK71
J 0
(-3390 1160);
DISPLAY 0.617021 (-3390 1160);
PAINT ORANGE (-3390 1160);
FORCEPROP 2 LASTPIN (-3400 1200) $PN AK69
J 0
(-3390 1210);
DISPLAY 0.617021 (-3390 1210);
PAINT ORANGE (-3390 1210);
FORCEPROP 2 LASTPIN (-3400 1300) $PN AK58
J 0
(-3390 1310);
DISPLAY 0.617021 (-3390 1310);
PAINT ORANGE (-3390 1310);
FORCEPROP 2 LASTPIN (-3400 1350) $PN AK48
J 0
(-3390 1360);
DISPLAY 0.617021 (-3390 1360);
PAINT ORANGE (-3390 1360);
FORCEPROP 2 LASTPIN (-3400 1400) $PN AK46
J 0
(-3390 1410);
DISPLAY 0.617021 (-3390 1410);
PAINT ORANGE (-3390 1410);
FORCEPROP 2 LASTPIN (-3400 1450) $PN AK41
J 0
(-3390 1460);
DISPLAY 0.617021 (-3390 1460);
PAINT ORANGE (-3390 1460);
FORCEPROP 2 LASTPIN (-3400 1500) $PN AK26
J 0
(-3390 1510);
DISPLAY 0.617021 (-3390 1510);
PAINT ORANGE (-3390 1510);
FORCEPROP 2 LASTPIN (-3400 1550) $PN AJ7
J 0
(-3390 1560);
DISPLAY 0.617021 (-3390 1560);
PAINT ORANGE (-3390 1560);
FORCEPROP 2 LASTPIN (-3400 1650) $PN AJ66
J 0
(-3390 1660);
DISPLAY 0.617021 (-3390 1660);
PAINT ORANGE (-3390 1660);
FORCEPROP 2 LASTPIN (-3400 1700) $PN AJ59
J 0
(-3390 1710);
DISPLAY 0.617021 (-3390 1710);
PAINT ORANGE (-3390 1710);
FORCEPROP 2 LASTPIN (-3400 1750) $PN AJ52
J 0
(-3390 1760);
DISPLAY 0.617021 (-3390 1760);
PAINT ORANGE (-3390 1760);
FORCEPROP 2 LASTPIN (-3400 1800) $PN AJ5
J 0
(-3390 1810);
DISPLAY 0.617021 (-3390 1810);
PAINT ORANGE (-3390 1810);
FORCEPROP 2 LASTPIN (-3400 1850) $PN AJ41
J 0
(-3390 1860);
DISPLAY 0.617021 (-3390 1860);
PAINT ORANGE (-3390 1860);
FORCEPROP 2 LASTPIN (-3400 1900) $PN AJ39
J 0
(-3390 1910);
DISPLAY 0.617021 (-3390 1910);
PAINT ORANGE (-3390 1910);
FORCEPROP 2 LASTPIN (-3400 1950) $PN AJ37
J 0
(-3390 1960);
DISPLAY 0.617021 (-3390 1960);
PAINT ORANGE (-3390 1960);
FORCEPROP 2 LASTPIN (-3400 2000) $PN AJ36
J 0
(-3390 2010);
DISPLAY 0.617021 (-3390 2010);
PAINT ORANGE (-3390 2010);
FORCEPROP 2 LASTPIN (-3400 2050) $PN AJ34
J 0
(-3390 2060);
DISPLAY 0.617021 (-3390 2060);
PAINT ORANGE (-3390 2060);
FORCEPROP 2 LASTPIN (-3400 2100) $PN AJ30
J 0
(-3390 2110);
DISPLAY 0.617021 (-3390 2110);
PAINT ORANGE (-3390 2110);
FORCEPROP 2 LASTPIN (-3400 2150) $PN AJ26
J 0
(-3390 2160);
DISPLAY 0.617021 (-3390 2160);
PAINT ORANGE (-3390 2160);
FORCEPROP 2 LASTPIN (-3400 2200) $PN AJ22
J 0
(-3390 2210);
DISPLAY 0.617021 (-3390 2210);
PAINT ORANGE (-3390 2210);
FORCEPROP 2 LASTPIN (-3400 2250) $PN AJ18
J 0
(-3390 2260);
DISPLAY 0.617021 (-3390 2260);
PAINT ORANGE (-3390 2260);
FORCEPROP 2 LASTPIN (-3400 2300) $PN AJ15
J 0
(-3390 2310);
DISPLAY 0.617021 (-3390 2310);
PAINT ORANGE (-3390 2310);
FORCEPROP 2 LASTPIN (-3400 2350) $PN AK30
J 0
(-3390 2360);
DISPLAY 0.617021 (-3390 2360);
PAINT ORANGE (-3390 2360);
FORCEPROP 2 LASTPIN (-3400 2400) $PN AJ56
J 0
(-3390 2410);
DISPLAY 0.617021 (-3390 2410);
PAINT ORANGE (-3390 2410);
FORCEPROP 2 LASTPIN (-3400 2450) $PN AJ32
J 0
(-3390 2460);
DISPLAY 0.617021 (-3390 2460);
PAINT ORANGE (-3390 2460);
FORCEPROP 2 LASTPIN (-3400 2500) $PN AJ11
J 0
(-3390 2510);
DISPLAY 0.617021 (-3390 2510);
PAINT ORANGE (-3390 2510);
FORCEPROP 2 LASTPIN (-3400 2550) $PN AH20
J 0
(-3390 2560);
DISPLAY 0.617021 (-3390 2560);
PAINT ORANGE (-3390 2560);
FORCEPROP 2 LASTPIN (-3400 2600) $PN AG66
J 0
(-3390 2610);
DISPLAY 0.617021 (-3390 2610);
PAINT ORANGE (-3390 2610);
FORCEPROP 2 LASTPIN (-3400 2650) $PN AG59
J 0
(-3390 2660);
DISPLAY 0.617021 (-3390 2660);
PAINT ORANGE (-3390 2660);
FORCEPROP 2 LASTPIN (-3400 2700) $PN AG56
J 0
(-3390 2710);
DISPLAY 0.617021 (-3390 2710);
PAINT ORANGE (-3390 2710);
FORCEPROP 2 LASTPIN (-3400 2750) $PN AG52
J 0
(-3390 2760);
DISPLAY 0.617021 (-3390 2760);
PAINT ORANGE (-3390 2760);
FORCEPROP 2 LASTPIN (-3400 2800) $PN AG43
J 0
(-3390 2810);
DISPLAY 0.617021 (-3390 2810);
PAINT ORANGE (-3390 2810);
FORCEPROP 2 LASTPIN (-3400 2850) $PN AG41
J 0
(-3390 2860);
DISPLAY 0.617021 (-3390 2860);
PAINT ORANGE (-3390 2860);
FORCEPROP 2 LASTPIN (-3400 2900) $PN AG30
J 0
(-3390 2910);
DISPLAY 0.617021 (-3390 2910);
PAINT ORANGE (-3390 2910);
FORCEPROP 2 LASTPIN (-3400 2950) $PN AG26
J 0
(-3390 2960);
DISPLAY 0.617021 (-3390 2960);
PAINT ORANGE (-3390 2960);
FORCEPROP 2 LASTPIN (-3400 3000) $PN AF68
J 0
(-3390 3010);
DISPLAY 0.617021 (-3390 3010);
PAINT ORANGE (-3390 3010);
FORCEPROP 2 LASTPIN (-3400 3050) $PN AF3
J 0
(-3390 3060);
DISPLAY 0.617021 (-3390 3060);
PAINT ORANGE (-3390 3060);
FORCEPROP 2 LASTPIN (-3400 3100) $PN AF24
J 0
(-3390 3110);
DISPLAY 0.617021 (-3390 3110);
PAINT ORANGE (-3390 3110);
FORCEPROP 2 LASTPIN (-3400 3150) $PN AF17
J 0
(-3390 3160);
DISPLAY 0.617021 (-3390 3160);
PAINT ORANGE (-3390 3160);
FORCEPROP 2 LASTPIN (-3400 3200) $PN AF9
J 0
(-3390 3210);
DISPLAY 0.617021 (-3390 3210);
PAINT ORANGE (-3390 3210);
FORCEPROP 2 LASTPIN (-3400 3250) $PN AF5
J 0
(-3390 3260);
DISPLAY 0.617021 (-3390 3260);
PAINT ORANGE (-3390 3260);
FORCEPROP 2 LASTPIN (-3400 3300) $PN AF13
J 0
(-3390 3310);
DISPLAY 0.617021 (-3390 3310);
PAINT ORANGE (-3390 3310);
FORCEPROP 2 LASTPIN (-3400 3350) $PN AF1
J 0
(-3390 3360);
DISPLAY 0.617021 (-3390 3360);
PAINT ORANGE (-3390 3360);
FORCEPROP 2 LASTPIN (-3400 3400) $PN AE66
J 0
(-3390 3410);
DISPLAY 0.617021 (-3390 3410);
PAINT ORANGE (-3390 3410);
FORCEPROP 2 LASTPIN (-3400 3450) $PN AE63
J 0
(-3390 3460);
DISPLAY 0.617021 (-3390 3460);
PAINT ORANGE (-3390 3460);
FORCEPROP 2 LASTPIN (-3400 3500) $PN AE59
J 0
(-3390 3510);
DISPLAY 0.617021 (-3390 3510);
PAINT ORANGE (-3390 3510);
FORCEPROP 2 LASTPIN (-3400 3550) $PN AE56
J 0
(-3390 3560);
DISPLAY 0.617021 (-3390 3560);
PAINT ORANGE (-3390 3560);
FORCEPROP 2 LASTPIN (-3400 3600) $PN AE52
J 0
(-3390 3610);
DISPLAY 0.617021 (-3390 3610);
PAINT ORANGE (-3390 3610);
FORCEPROP 2 LASTPIN (-3400 3650) $PN AE48
J 0
(-3390 3660);
DISPLAY 0.617021 (-3390 3660);
PAINT ORANGE (-3390 3660);
FORCEPROP 2 LASTPIN (-3400 3700) $PN J18
J 0
(-3390 3710);
DISPLAY 0.617021 (-3390 3710);
PAINT ORANGE (-3390 3710);
FORCEPROP 2 LASTPIN (-3400 3750) $PN AE29
J 0
(-3390 3760);
DISPLAY 0.617021 (-3390 3760);
PAINT ORANGE (-3390 3760);
FORCEPROP 2 LASTPIN (-3400 3800) $PN AD68
J 0
(-3390 3810);
DISPLAY 0.617021 (-3390 3810);
PAINT ORANGE (-3390 3810);
FORCEPROP 2 LASTPIN (-3400 3850) $PN AD65
J 0
(-3390 3860);
DISPLAY 0.617021 (-3390 3860);
PAINT ORANGE (-3390 3860);
FORCEPROP 2 LASTPIN (-3400 3900) $PN AD5
J 0
(-3390 3910);
DISPLAY 0.617021 (-3390 3910);
PAINT ORANGE (-3390 3910);
FORCEPROP 2 LASTPIN (-3400 3950) $PN AC7
J 0
(-3390 3960);
DISPLAY 0.617021 (-3390 3960);
PAINT ORANGE (-3390 3960);
FORCEPROP 2 LASTPIN (-3400 4000) $PN AC66
J 0
(-3390 4010);
DISPLAY 0.617021 (-3390 4010);
PAINT ORANGE (-3390 4010);
FORCEPROP 2 LASTPIN (-3400 4050) $PN AC63
J 0
(-3390 4060);
DISPLAY 0.617021 (-3390 4060);
PAINT ORANGE (-3390 4060);
FORCEPROP 2 LASTPIN (-3400 4100) $PN AC59
J 0
(-3390 4110);
DISPLAY 0.617021 (-3390 4110);
PAINT ORANGE (-3390 4110);
FORCEPROP 2 LASTPIN (-3400 4150) $PN AC52
J 0
(-3390 4160);
DISPLAY 0.617021 (-3390 4160);
PAINT ORANGE (-3390 4160);
FORCEPROP 2 LASTPIN (-3400 4250) $PN AC46
J 0
(-3390 4260);
DISPLAY 0.617021 (-3390 4260);
PAINT ORANGE (-3390 4260);
FORCEPROP 2 LASTPIN (-3400 4300) $PN AC43
J 0
(-3390 4310);
DISPLAY 0.617021 (-3390 4310);
PAINT ORANGE (-3390 4310);
FORCEPROP 2 LASTPIN (-3400 4350) $PN AC27
J 0
(-3390 4360);
DISPLAY 0.617021 (-3390 4360);
PAINT ORANGE (-3390 4360);
FORCEPROP 2 LASTPIN (-3400 4400) $PN AD58
J 0
(-3390 4410);
DISPLAY 0.617021 (-3390 4410);
PAINT ORANGE (-3390 4410);
FORCEPROP 2 LASTPIN (-4600 1000) $PN AC22
J 2
(-4610 1010);
DISPLAY 0.617021 (-4610 1010);
PAINT ORANGE (-4610 1010);
FORCEPROP 2 LASTPIN (-4600 1050) $PN AC18
J 2
(-4610 1060);
DISPLAY 0.617021 (-4610 1060);
PAINT ORANGE (-4610 1060);
FORCEPROP 2 LASTPIN (-4600 1100) $PN AC15
J 2
(-4610 1110);
DISPLAY 0.617021 (-4610 1110);
PAINT ORANGE (-4610 1110);
FORCEPROP 2 LASTPIN (-4600 1150) $PN AC11
J 2
(-4610 1160);
DISPLAY 0.617021 (-4610 1160);
PAINT ORANGE (-4610 1160);
FORCEPROP 2 LASTPIN (-4600 1250) $PN AB70
J 2
(-4610 1260);
DISPLAY 0.617021 (-4610 1260);
PAINT ORANGE (-4610 1260);
FORCEPROP 2 LASTPIN (-4600 1450) $PN AA43
J 2
(-4610 1460);
DISPLAY 0.617021 (-4610 1460);
PAINT ORANGE (-4610 1460);
FORCEPROP 2 LASTPIN (-4600 1500) $PN AA27
J 2
(-4610 1510);
DISPLAY 0.617021 (-4610 1510);
PAINT ORANGE (-4610 1510);
FORCEPROP 2 LASTPIN (-4600 1550) $PN AA26
J 2
(-4610 1560);
DISPLAY 0.617021 (-4610 1560);
PAINT ORANGE (-4610 1560);
FORCEPROP 2 LASTPIN (-4600 1600) $PN Y68
J 2
(-4610 1610);
DISPLAY 0.617021 (-4610 1610);
PAINT ORANGE (-4610 1610);
FORCEPROP 2 LASTPIN (-4600 1650) $PN Y63
J 2
(-4610 1660);
DISPLAY 0.617021 (-4610 1660);
PAINT ORANGE (-4610 1660);
FORCEPROP 2 LASTPIN (-4600 1700) $PN Y59
J 2
(-4610 1710);
DISPLAY 0.617021 (-4610 1710);
PAINT ORANGE (-4610 1710);
FORCEPROP 2 LASTPIN (-4600 1750) $PN Y52
J 2
(-4610 1760);
DISPLAY 0.617021 (-4610 1760);
PAINT ORANGE (-4610 1760);
FORCEPROP 2 LASTPIN (-4600 1800) $PN Y5
J 2
(-4610 1810);
DISPLAY 0.617021 (-4610 1810);
PAINT ORANGE (-4610 1810);
FORCEPROP 2 LASTPIN (-4600 1850) $PN Y48
J 2
(-4610 1860);
DISPLAY 0.617021 (-4610 1860);
PAINT ORANGE (-4610 1860);
FORCEPROP 2 LASTPIN (-4600 1900) $PN Y27
J 2
(-4610 1910);
DISPLAY 0.617021 (-4610 1910);
PAINT ORANGE (-4610 1910);
FORCEPROP 2 LASTPIN (-4600 1950) $PN Y22
J 2
(-4610 1960);
DISPLAY 0.617021 (-4610 1960);
PAINT ORANGE (-4610 1960);
FORCEPROP 2 LASTPIN (-4600 2000) $PN W9
J 2
(-4610 2010);
DISPLAY 0.617021 (-4610 2010);
PAINT ORANGE (-4610 2010);
FORCEPROP 2 LASTPIN (-4600 2050) $PN W61
J 2
(-4610 2060);
DISPLAY 0.617021 (-4610 2060);
PAINT ORANGE (-4610 2060);
FORCEPROP 2 LASTPIN (-4600 2100) $PN Y43
J 2
(-4610 2110);
DISPLAY 0.617021 (-4610 2110);
PAINT ORANGE (-4610 2110);
FORCEPROP 2 LASTPIN (-4600 2150) $PN AA50
J 2
(-4610 2160);
DISPLAY 0.617021 (-4610 2160);
PAINT ORANGE (-4610 2160);
FORCEPROP 2 LASTPIN (-4600 2200) $PN W24
J 2
(-4610 2210);
DISPLAY 0.617021 (-4610 2210);
PAINT ORANGE (-4610 2210);
FORCEPROP 2 LASTPIN (-4600 2250) $PN W20
J 2
(-4610 2260);
DISPLAY 0.617021 (-4610 2260);
PAINT ORANGE (-4610 2260);
FORCEPROP 2 LASTPIN (-4600 2300) $PN W17
J 2
(-4610 2310);
DISPLAY 0.617021 (-4610 2310);
PAINT ORANGE (-4610 2310);
FORCEPROP 2 LASTPIN (-4600 2350) $PN W13
J 2
(-4610 2360);
DISPLAY 0.617021 (-4610 2360);
PAINT ORANGE (-4610 2360);
FORCEPROP 2 LASTPIN (-4600 2400) $PN V68
J 2
(-4610 2410);
DISPLAY 0.617021 (-4610 2410);
PAINT ORANGE (-4610 2410);
FORCEPROP 2 LASTPIN (-4600 2450) $PN V66
J 2
(-4610 2460);
DISPLAY 0.617021 (-4610 2460);
PAINT ORANGE (-4610 2460);
FORCEPROP 2 LASTPIN (-4600 2500) $PN W58
J 2
(-4610 2510);
DISPLAY 0.617021 (-4610 2510);
PAINT ORANGE (-4610 2510);
FORCEPROP 2 LASTPIN (-4600 2550) $PN V52
J 2
(-4610 2560);
DISPLAY 0.617021 (-4610 2560);
PAINT ORANGE (-4610 2560);
FORCEPROP 2 LASTPIN (-4600 2600) $PN V5
J 2
(-4610 2610);
DISPLAY 0.617021 (-4610 2610);
PAINT ORANGE (-4610 2610);
FORCEPROP 2 LASTPIN (-4600 2650) $PN V48
J 2
(-4610 2660);
DISPLAY 0.617021 (-4610 2660);
PAINT ORANGE (-4610 2660);
FORCEPROP 2 LASTPIN (-4600 2750) $PN U58
J 2
(-4610 2760);
DISPLAY 0.617021 (-4610 2760);
PAINT ORANGE (-4610 2760);
FORCEPROP 2 LASTPIN (-4600 2800) $PN AG46
J 2
(-4610 2810);
DISPLAY 0.617021 (-4610 2810);
PAINT ORANGE (-4610 2810);
FORCEPROP 2 LASTPIN (-4600 2850) $PN AF50
J 2
(-4610 2860);
DISPLAY 0.617021 (-4610 2860);
PAINT ORANGE (-4610 2860);
FORCEPROP 2 LASTPIN (-4600 2900) $PN T7
J 2
(-4610 2910);
DISPLAY 0.617021 (-4610 2910);
PAINT ORANGE (-4610 2910);
FORCEPROP 2 LASTPIN (-4600 2950) $PN T66
J 2
(-4610 2960);
DISPLAY 0.617021 (-4610 2960);
PAINT ORANGE (-4610 2960);
FORCEPROP 2 LASTPIN (-4600 3000) $PN T52
J 2
(-4610 3010);
DISPLAY 0.617021 (-4610 3010);
PAINT ORANGE (-4610 3010);
FORCEPROP 2 LASTPIN (-4600 3050) $PN T48
J 2
(-4610 3060);
DISPLAY 0.617021 (-4610 3060);
PAINT ORANGE (-4610 3060);
FORCEPROP 2 LASTPIN (-4600 3100) $PN AJ45
J 2
(-4610 3110);
DISPLAY 0.617021 (-4610 3110);
PAINT ORANGE (-4610 3110);
FORCEPROP 2 LASTPIN (-4600 3150) $PN T40
J 2
(-4610 3160);
DISPLAY 0.617021 (-4610 3160);
PAINT ORANGE (-4610 3160);
FORCEPROP 2 LASTPIN (-4600 3200) $PN T37
J 2
(-4610 3210);
DISPLAY 0.617021 (-4610 3210);
PAINT ORANGE (-4610 3210);
FORCEPROP 2 LASTPIN (-4600 3250) $PN T33
J 2
(-4610 3260);
DISPLAY 0.617021 (-4610 3260);
PAINT ORANGE (-4610 3260);
FORCEPROP 2 LASTPIN (-4600 3300) $PN T29
J 2
(-4610 3310);
DISPLAY 0.617021 (-4610 3310);
PAINT ORANGE (-4610 3310);
FORCEPROP 2 LASTPIN (-4600 3350) $PN T26
J 2
(-4610 3360);
DISPLAY 0.617021 (-4610 3360);
PAINT ORANGE (-4610 3360);
FORCEPROP 2 LASTPIN (-4600 3400) $PN T22
J 2
(-4610 3410);
DISPLAY 0.617021 (-4610 3410);
PAINT ORANGE (-4610 3410);
FORCEPROP 2 LASTPIN (-4600 3450) $PN T18
J 2
(-4610 3460);
DISPLAY 0.617021 (-4610 3460);
PAINT ORANGE (-4610 3460);
FORCEPROP 2 LASTPIN (-4600 3500) $PN T15
J 2
(-4610 3510);
DISPLAY 0.617021 (-4610 3510);
PAINT ORANGE (-4610 3510);
FORCEPROP 2 LASTPIN (-4600 3550) $PN T11
J 2
(-4610 3560);
DISPLAY 0.617021 (-4610 3560);
PAINT ORANGE (-4610 3560);
FORCEPROP 2 LASTPIN (-4600 3600) $PN R68
J 2
(-4610 3610);
DISPLAY 0.617021 (-4610 3610);
PAINT ORANGE (-4610 3610);
FORCEPROP 2 LASTPIN (-4600 3650) $PN R58
J 2
(-4610 3660);
DISPLAY 0.617021 (-4610 3660);
PAINT ORANGE (-4610 3660);
FORCEPROP 2 LASTPIN (-4600 3700) $PN T56
J 2
(-4610 3710);
DISPLAY 0.617021 (-4610 3710);
PAINT ORANGE (-4610 3710);
FORCEPROP 2 LASTPIN (-4600 3750) $PN R54
J 2
(-4610 3760);
DISPLAY 0.617021 (-4610 3760);
PAINT ORANGE (-4610 3760);
FORCEPROP 2 LASTPIN (-4600 3800) $PN R50
J 2
(-4610 3810);
DISPLAY 0.617021 (-4610 3810);
PAINT ORANGE (-4610 3810);
FORCEPROP 2 LASTPIN (-4600 3850) $PN R5
J 2
(-4610 3860);
DISPLAY 0.617021 (-4610 3860);
PAINT ORANGE (-4610 3860);
FORCEPROP 2 LASTPIN (-4600 3900) $PN U42
J 2
(-4610 3910);
DISPLAY 0.617021 (-4610 3910);
PAINT ORANGE (-4610 3910);
FORCEPROP 2 LASTPIN (-4600 3950) $PN R27
J 2
(-4610 3960);
DISPLAY 0.617021 (-4610 3960);
PAINT ORANGE (-4610 3960);
FORCEPROP 2 LASTPIN (-4600 4000) $PN P63
J 2
(-4610 4010);
DISPLAY 0.617021 (-4610 4010);
PAINT ORANGE (-4610 4010);
FORCEPROP 2 LASTPIN (-4600 4050) $PN AE43
J 2
(-4610 4060);
DISPLAY 0.617021 (-4610 4060);
PAINT ORANGE (-4610 4060);
FORCEPROP 2 LASTPIN (-4600 4100) $PN N9
J 2
(-4610 4110);
DISPLAY 0.617021 (-4610 4110);
PAINT ORANGE (-4610 4110);
FORCEPROP 2 LASTPIN (-4600 4150) $PN N68
J 2
(-4610 4160);
DISPLAY 0.617021 (-4610 4160);
PAINT ORANGE (-4610 4160);
FORCEPROP 2 LASTPIN (-4600 4200) $PN R38
J 2
(-4610 4210);
DISPLAY 0.617021 (-4610 4210);
PAINT ORANGE (-4610 4210);
FORCEPROP 2 LASTPIN (-4600 4250) $PN N5
J 2
(-4610 4260);
DISPLAY 0.617021 (-4610 4260);
PAINT ORANGE (-4610 4260);
FORCEPROP 2 LASTPIN (-4600 4300) $PN N46
J 2
(-4610 4310);
DISPLAY 0.617021 (-4610 4310);
PAINT ORANGE (-4610 4310);
FORCEPROP 2 LASTPIN (-4600 4350) $PN N38
J 2
(-4610 4360);
DISPLAY 0.617021 (-4610 4360);
PAINT ORANGE (-4610 4360);
FORCEPROP 2 LASTPIN (-4600 4400) $PN N35
J 2
(-4610 4410);
DISPLAY 0.617021 (-4610 4410);
PAINT ORANGE (-4610 4410);
FORCEPROP 2 LASTPIN (-4600 950) $PN AC45
J 2
(-4610 960);
DISPLAY 0.617021 (-4610 960);
PAINT ORANGE (-4610 960);
FORCEPROP 2 LASTPIN (-4600 1400) $PN AA48
J 2
(-4610 1410);
DISPLAY 0.617021 (-4610 1410);
PAINT ORANGE (-4610 1410);
FORCEPROP 2 LASTPIN (-4600 1350) $PN AB5
J 2
(-4610 1360);
DISPLAY 0.617021 (-4610 1360);
PAINT ORANGE (-4610 1360);
FORCEPROP 2 LASTPIN (-4600 1300) $PN AB68
J 2
(-4610 1310);
DISPLAY 0.617021 (-4610 1310);
PAINT ORANGE (-4610 1310);
FORCEPROP 2 LASTPIN (-3400 1250) $PN AK61
J 0
(-3390 1260);
DISPLAY 0.617021 (-3390 1260);
PAINT ORANGE (-3390 1260);
FORCEPROP 2 LASTPIN (-4600 1200) $PN AB72
J 2
(-4610 1210);
DISPLAY 0.617021 (-4610 1210);
PAINT ORANGE (-4610 1210);
FORCEPROP 2 LASTPIN (-3400 4200) $PN AC48
J 0
(-3390 4210);
DISPLAY 0.617021 (-3390 4210);
PAINT ORANGE (-3390 4210);
FORCEPROP 1 LAST LOCATION U7C1
J 0
(-4500 4725);
DISPLAY 0.617021 (-4500 4725);
PAINT AQUA (-4500 4725);
FORCEPROP 2 LASTPIN (-4600 2700) $PN V26
J 2
(-4610 2710);
DISPLAY 0.617021 (-4610 2710);
PAINT ORANGE (-4610 2710);
FORCEPROP 1 LAST PACK_TYPE BGA1
J 0
(-4550 4700);
PAINT SKYBLUE (-4550 4700);
DISPLAY INVISIBLE (-4550 4700);
FORCEPROP 2 LAST SEC_TYPE BGA1
J 0
(-4500 4775);
DISPLAY 1.021277 (-4500 4775);
PAINT ORANGE (-4500 4775);
DISPLAY INVISIBLE (-4500 4775);
FORCEPROP 2 LAST SEC 12
J 0
(-4500 4775);
DISPLAY 0.680851 (-4500 4775);
PAINT MONO (-4500 4775);
DISPLAY INVISIBLE (-4500 4775);
FORCEPROP 2 LAST CDS_LIB mstr_u_proc
J 0
(-4000 2700);
PAINT ORANGE (-4000 2700);
DISPLAY INVISIBLE (-4000 2700);
FORCEPROP 0 LAST BOM_COST SB
J 0
(-4550 4650);
DISPLAY 1.361702 (-4550 4650);
PAINT ORANGE (-4550 4650);
DISPLAY INVISIBLE (-4550 4650);
FORCEPROP 2 LAST CDS_LOCATION U7C1
J 0
(-4500 4725);
DISPLAY 0.617021 (-4500 4725);
PAINT AQUA (-4500 4725);
DISPLAY INVISIBLE (-4500 4725);
FORCEPROP 1 LAST PATH I17
J 0
(-4000 4600);
PAINT GREEN (-4000 4600);
DISPLAY INVISIBLE (-4000 4600);
FORCEPROP 0 LAST ROOM SB
J 0
(-4550 4550);
DISPLAY 1.361702 (-4550 4550);
PAINT ORANGE (-4550 4550);
DISPLAY INVISIBLE (-4550 4550);
FORCEADD GND..1
(-3125 600);
FORCEPROP 3 LASTPIN (-3125 650) SIG_NAME GND\g
J 0
(-3115 660);
DISPLAY 0.659574 (-3115 660);
PAINT MONO (-3115 660);
DISPLAY INVISIBLE (-3115 660);
FORCEPROP 1 LAST VOLTAGE 0.0V
J 0
(-3170 557);
DISPLAY 0.340426 (-3170 557);
PAINT SKYBLUE (-3170 557);
DISPLAY INVISIBLE (-3170 557);
FORCEPROP 1 LAST SIZE 1B
J 0
(-3050 550);
DISPLAY 1.170213 (-3050 550);
PAINT AQUA (-3050 550);
DISPLAY INVISIBLE (-3050 550);
FORCEPROP 2 LAST CDS_LIB mstr_symbols
J 0
(-3125 600);
PAINT ORANGE (-3125 600);
DISPLAY INVISIBLE (-3125 600);
FORCEPROP 1 LAST BODY_TYPE PLUMBING
J 0
(-3170 557);
DISPLAY 0.340426 (-3170 557);
PAINT GREEN (-3170 557);
DISPLAY INVISIBLE (-3170 557);
FORCEPROP 1 LAST PATH I4
J 0
(-3050 600);
DISPLAY 1.170213 (-3050 600);
PAINT AQUA (-3050 600);
DISPLAY INVISIBLE (-3050 600);
FORCEPROP 1 LAST HDL_POWER GND
J 0
(-3125 750);
DISPLAY 1.170213 (-3125 750);
PAINT GREEN (-3125 750);
DISPLAY INVISIBLE (-3125 750);
FORCEADD GND..1
(-4950 600);
FORCEPROP 3 LASTPIN (-4950 650) SIG_NAME GND\g
J 0
(-4940 660);
DISPLAY 0.659574 (-4940 660);
PAINT MONO (-4940 660);
DISPLAY INVISIBLE (-4940 660);
FORCEPROP 1 LAST VOLTAGE 0.0V
J 0
(-4995 557);
DISPLAY 0.340426 (-4995 557);
PAINT SKYBLUE (-4995 557);
DISPLAY INVISIBLE (-4995 557);
FORCEPROP 1 LAST SIZE 1B
J 0
(-4875 550);
DISPLAY 1.170213 (-4875 550);
PAINT AQUA (-4875 550);
DISPLAY INVISIBLE (-4875 550);
FORCEPROP 2 LAST CDS_LIB mstr_symbols
J 0
(-4950 600);
PAINT ORANGE (-4950 600);
DISPLAY INVISIBLE (-4950 600);
FORCEPROP 1 LAST BODY_TYPE PLUMBING
J 0
(-4995 557);
DISPLAY 0.340426 (-4995 557);
PAINT GREEN (-4995 557);
DISPLAY INVISIBLE (-4995 557);
FORCEPROP 1 LAST PATH I6
J 0
(-4875 600);
DISPLAY 1.170213 (-4875 600);
PAINT AQUA (-4875 600);
DISPLAY INVISIBLE (-4875 600);
FORCEPROP 1 LAST HDL_POWER GND
J 0
(-4950 750);
DISPLAY 1.170213 (-4950 750);
PAINT GREEN (-4950 750);
DISPLAY INVISIBLE (-4950 750);
FORCEADD GND..1
(-400 575);
FORCEPROP 3 LASTPIN (-400 625) SIG_NAME GND\g
J 0
(-390 635);
DISPLAY 0.659574 (-390 635);
PAINT MONO (-390 635);
DISPLAY INVISIBLE (-390 635);
FORCEPROP 1 LAST VOLTAGE 0.0V
J 0
(-445 532);
DISPLAY 0.340426 (-445 532);
PAINT SKYBLUE (-445 532);
DISPLAY INVISIBLE (-445 532);
FORCEPROP 2 LAST CDS_LIB mstr_symbols
J 0
(-400 575);
PAINT ORANGE (-400 575);
DISPLAY INVISIBLE (-400 575);
FORCEPROP 1 LAST SIZE 1B
J 0
(-325 525);
DISPLAY 1.170213 (-325 525);
PAINT AQUA (-325 525);
DISPLAY INVISIBLE (-325 525);
FORCEPROP 1 LAST BODY_TYPE PLUMBING
J 0
(-445 532);
DISPLAY 0.340426 (-445 532);
PAINT GREEN (-445 532);
DISPLAY INVISIBLE (-445 532);
FORCEPROP 1 LAST PATH I7
J 0
(-325 575);
DISPLAY 1.170213 (-325 575);
PAINT AQUA (-325 575);
DISPLAY INVISIBLE (-325 575);
FORCEPROP 1 LAST HDL_POWER GND
J 0
(-400 725);
DISPLAY 1.170213 (-400 725);
PAINT GREEN (-400 725);
DISPLAY INVISIBLE (-400 725);
FORCEADD GND..1
(-2550 625);
FORCEPROP 3 LASTPIN (-2550 675) SIG_NAME GND\g
J 0
(-2540 685);
DISPLAY 0.659574 (-2540 685);
PAINT MONO (-2540 685);
DISPLAY INVISIBLE (-2540 685);
FORCEPROP 1 LAST VOLTAGE 0.0V
J 0
(-2595 582);
DISPLAY 0.340426 (-2595 582);
PAINT SKYBLUE (-2595 582);
DISPLAY INVISIBLE (-2595 582);
FORCEPROP 1 LAST SIZE 1B
J 0
(-2475 575);
DISPLAY 1.170213 (-2475 575);
PAINT AQUA (-2475 575);
DISPLAY INVISIBLE (-2475 575);
FORCEPROP 2 LAST CDS_LIB mstr_symbols
J 0
(-2550 625);
PAINT ORANGE (-2550 625);
DISPLAY INVISIBLE (-2550 625);
FORCEPROP 1 LAST BODY_TYPE PLUMBING
J 0
(-2595 582);
DISPLAY 0.340426 (-2595 582);
PAINT GREEN (-2595 582);
DISPLAY INVISIBLE (-2595 582);
FORCEPROP 1 LAST PATH I9
J 0
(-2475 625);
DISPLAY 1.170213 (-2475 625);
PAINT AQUA (-2475 625);
DISPLAY INVISIBLE (-2475 625);
FORCEPROP 1 LAST HDL_POWER GND
J 0
(-2550 775);
DISPLAY 1.170213 (-2550 775);
PAINT GREEN (-2550 775);
DISPLAY INVISIBLE (-2550 775);
FORCEADD INTEL_CORP_BPAGE..1
(2525 0);
FORCEPROP 1 LAST CDS_CON_LAST_MODIFIED Fri Jun 16 17:48:48 2017
J 0
(1100 325);
DISPLAY 1.340426 (1100 325);
PAINT GREEN (1100 325);
DISPLAY INVISIBLE (1100 325);
FORCEPROP 1 LAST CUSTOM_TXT_CDS <CURRENT_DESIGN_SHEET> OF <TOTAL_DESIGN_SHEETS>
J 0
(2025 25);
PAINT ORANGE (2025 25);
FORCEPROP 1 LAST CUSTOM_TXT_CDS <CON_LAST_MODIFIED>
J 0
(-1475 100);
PAINT ORANGE (-1475 100);
FORCEPROP 2 LAST CUSTOM_TXT_CDS <XR_PAGE_TITLE>
J 0
(-5365 5250);
DISPLAY 0.638298 (-5365 5250);
PAINT PINK (-5365 5250);
DISPLAY INVISIBLE (-5365 5250);
FORCEPROP 1 LAST SCH_TITLE LEWISBURG 11/11 GND
J 0
(-5425 50);
DISPLAY 1.212766 (-5425 50);
PAINT GREEN (-5425 50);
FORCEPROP 2 LAST PAGE_BORDER TRUE
J 0
(-5365 5250);
DISPLAY 0.851064 (-5365 5250);
PAINT PINK (-5365 5250);
DISPLAY INVISIBLE (-5365 5250);
FORCEPROP 2 LAST CDS_LIB mstr_symbols
J 0
(2525 0);
PAINT ORANGE (2525 0);
DISPLAY INVISIBLE (2525 0);
FORCEPROP 1 LAST COMMENT_BODY TRUE
J 0
(2537 12);
DISPLAY 0.638298 (2537 12);
PAINT GREEN (2537 12);
DISPLAY INVISIBLE (2537 12);
FORCEPROP 2 LAST CDS_XR_PAGE_TITLE CR-124 : @BASEBOARD_FAB2_LIB.BASEBOARD_FAB2(SCH_1):PAGE124
J 0
(-5365 5250);
DISPLAY 0.638298 (-5365 5250);
PAINT PINK (-5365 5250);
DISPLAY INVISIBLE (-5365 5250);
WIRE 16 -1 (225 875)(225 950);
WIRE 16 -1 (225 950)(225 1000);
WIRE 16 -1 (225 950)(600 950);
WIRE 16 -1 (225 1050)(225 1000);
WIRE 16 -1 (600 1000)(225 1000);
WIRE 16 -1 (225 1100)(225 1050);
WIRE 16 -1 (600 1050)(225 1050);
WIRE 16 -1 (225 1150)(225 1100);
WIRE 16 -1 (600 1100)(225 1100);
WIRE 16 -1 (225 1200)(225 1150);
WIRE 16 -1 (600 1150)(225 1150);
WIRE 16 -1 (225 1250)(225 1200);
WIRE 16 -1 (600 1200)(225 1200);
WIRE 16 -1 (225 1300)(225 1250);
WIRE 16 -1 (600 1250)(225 1250);
WIRE 16 -1 (225 1300)(225 1350);
WIRE 16 -1 (600 1300)(225 1300);
WIRE 16 -1 (225 1400)(225 1350);
WIRE 16 -1 (600 1350)(225 1350);
WIRE 16 -1 (225 1450)(225 1400);
WIRE 16 -1 (600 1400)(225 1400);
WIRE 16 -1 (225 1500)(225 1450);
WIRE 16 -1 (600 1450)(225 1450);
WIRE 16 -1 (225 1550)(225 1500);
WIRE 16 -1 (600 1500)(225 1500);
WIRE 16 -1 (225 1600)(225 1550);
WIRE 16 -1 (600 1550)(225 1550);
WIRE 16 -1 (225 1650)(225 1600);
WIRE 16 -1 (600 1600)(225 1600);
WIRE 16 -1 (225 1650)(225 1700);
WIRE 16 -1 (600 1650)(225 1650);
WIRE 16 -1 (225 1750)(225 1700);
WIRE 16 -1 (600 1700)(225 1700);
WIRE 16 -1 (225 1800)(225 1750);
WIRE 16 -1 (600 1750)(225 1750);
WIRE 16 -1 (225 1850)(225 1800);
WIRE 16 -1 (600 1800)(225 1800);
WIRE 16 -1 (225 1900)(225 1850);
WIRE 16 -1 (600 1850)(225 1850);
WIRE 16 -1 (225 1950)(225 1900);
WIRE 16 -1 (600 1900)(225 1900);
WIRE 16 -1 (225 2000)(225 1950);
WIRE 16 -1 (600 1950)(225 1950);
WIRE 16 -1 (225 2000)(225 2050);
WIRE 16 -1 (600 2000)(225 2000);
WIRE 16 -1 (225 2100)(225 2050);
WIRE 16 -1 (600 2050)(225 2050);
WIRE 16 -1 (225 2150)(225 2100);
WIRE 16 -1 (600 2100)(225 2100);
WIRE 16 -1 (225 2200)(225 2150);
WIRE 16 -1 (600 2150)(225 2150);
WIRE 16 -1 (225 2250)(225 2200);
WIRE 16 -1 (600 2200)(225 2200);
WIRE 16 -1 (225 2300)(225 2250);
WIRE 16 -1 (600 2250)(225 2250);
WIRE 16 -1 (225 2350)(225 2300);
WIRE 16 -1 (600 2300)(225 2300);
WIRE 16 -1 (225 2400)(225 2350);
WIRE 16 -1 (600 2350)(225 2350);
WIRE 16 -1 (225 2450)(225 2400);
WIRE 16 -1 (600 2400)(225 2400);
WIRE 16 -1 (225 2500)(225 2450);
WIRE 16 -1 (600 2450)(225 2450);
WIRE 16 -1 (225 2550)(225 2500);
WIRE 16 -1 (600 2500)(225 2500);
WIRE 16 -1 (225 2600)(225 2550);
WIRE 16 -1 (600 2550)(225 2550);
WIRE 16 -1 (225 2650)(225 2600);
WIRE 16 -1 (600 2600)(225 2600);
WIRE 16 -1 (225 2700)(225 2650);
WIRE 16 -1 (600 2650)(225 2650);
WIRE 16 -1 (225 2750)(225 2700);
WIRE 16 -1 (600 2700)(225 2700);
WIRE 16 -1 (225 2800)(225 2750);
WIRE 16 -1 (600 2750)(225 2750);
WIRE 16 -1 (225 2850)(225 2800);
WIRE 16 -1 (600 2800)(225 2800);
WIRE 16 -1 (225 2900)(225 2850);
WIRE 16 -1 (600 2850)(225 2850);
WIRE 16 -1 (225 2950)(225 2900);
WIRE 16 -1 (600 2900)(225 2900);
WIRE 16 -1 (225 3000)(225 2950);
WIRE 16 -1 (600 2950)(225 2950);
WIRE 16 -1 (225 3050)(225 3000);
WIRE 16 -1 (600 3000)(225 3000);
WIRE 16 -1 (225 3100)(225 3050);
WIRE 16 -1 (600 3050)(225 3050);
WIRE 16 -1 (225 3150)(225 3100);
WIRE 16 -1 (600 3100)(225 3100);
WIRE 16 -1 (225 3200)(225 3150);
WIRE 16 -1 (600 3150)(225 3150);
WIRE 16 -1 (225 3250)(225 3200);
WIRE 16 -1 (600 3200)(225 3200);
WIRE 16 -1 (225 3300)(225 3250);
WIRE 16 -1 (600 3250)(225 3250);
WIRE 16 -1 (225 3350)(225 3300);
WIRE 16 -1 (600 3300)(225 3300);
WIRE 16 -1 (225 3400)(225 3350);
WIRE 16 -1 (600 3350)(225 3350);
WIRE 16 -1 (225 3450)(225 3400);
WIRE 16 -1 (600 3400)(225 3400);
WIRE 16 -1 (225 3500)(225 3450);
WIRE 16 -1 (600 3450)(225 3450);
WIRE 16 -1 (225 3550)(225 3500);
WIRE 16 -1 (600 3500)(225 3500);
WIRE 16 -1 (225 3600)(225 3550);
WIRE 16 -1 (600 3550)(225 3550);
WIRE 16 -1 (225 3600)(225 3650);
WIRE 16 -1 (600 3600)(225 3600);
WIRE 16 -1 (225 3700)(225 3650);
WIRE 16 -1 (600 3650)(225 3650);
WIRE 16 -1 (225 3750)(225 3700);
WIRE 16 -1 (600 3700)(225 3700);
WIRE 16 -1 (225 3800)(225 3750);
WIRE 16 -1 (600 3750)(225 3750);
WIRE 16 -1 (225 3850)(225 3800);
WIRE 16 -1 (600 3800)(225 3800);
WIRE 16 -1 (225 3900)(225 3850);
WIRE 16 -1 (600 3850)(225 3850);
WIRE 16 -1 (225 3950)(225 3900);
WIRE 16 -1 (600 3900)(225 3900);
WIRE 16 -1 (225 4000)(225 3950);
WIRE 16 -1 (600 3950)(225 3950);
WIRE 16 -1 (225 4000)(225 4050);
WIRE 16 -1 (600 4000)(225 4000);
WIRE 16 -1 (225 4100)(225 4050);
WIRE 16 -1 (600 4050)(225 4050);
WIRE 16 -1 (225 4150)(225 4100);
WIRE 16 -1 (600 4100)(225 4100);
WIRE 16 -1 (225 4200)(225 4150);
WIRE 16 -1 (600 4150)(225 4150);
WIRE 16 -1 (225 4250)(225 4200);
WIRE 16 -1 (600 4200)(225 4200);
WIRE 16 -1 (225 4300)(225 4250);
WIRE 16 -1 (600 4250)(225 4250);
WIRE 16 -1 (225 4350)(225 4300);
WIRE 16 -1 (600 4300)(225 4300);
WIRE 16 -1 (225 4350)(225 4400);
WIRE 16 -1 (600 4350)(225 4350);
WIRE 16 -1 (225 4400)(600 4400);
WIRE 16 -1 (2200 4125)(2200 4200);
WIRE 16 -1 (2200 4200)(2200 4250);
WIRE 16 -1 (1800 4200)(2200 4200);
WIRE 16 -1 (2200 4250)(2200 4300);
WIRE 16 -1 (1800 4250)(2200 4250);
WIRE 16 -1 (2200 4300)(2200 4350);
WIRE 16 -1 (1800 4300)(2200 4300);
WIRE 16 -1 (2200 4350)(2200 4400);
WIRE 16 -1 (1800 4350)(2200 4350);
WIRE 16 -1 (1800 4400)(2200 4400);
WIRE 16 -1 (-3125 650)(-3125 950);
WIRE 16 -1 (-3125 950)(-3125 1000);
WIRE 16 -1 (-3400 950)(-3125 950);
WIRE 16 -1 (-3125 1000)(-3125 1050);
WIRE 16 -1 (-3400 1000)(-3125 1000);
WIRE 16 -1 (-3125 1050)(-3125 1100);
WIRE 16 -1 (-3400 1050)(-3125 1050);
WIRE 16 -1 (-3125 1100)(-3125 1150);
WIRE 16 -1 (-3400 1100)(-3125 1100);
WIRE 16 -1 (-3125 1150)(-3125 1200);
WIRE 16 -1 (-3400 1150)(-3125 1150);
WIRE 16 -1 (-3125 1200)(-3125 1250);
WIRE 16 -1 (-3400 1200)(-3125 1200);
WIRE 16 -1 (-3125 1250)(-3125 1300);
WIRE 16 -1 (-3400 1250)(-3125 1250);
WIRE 16 -1 (-3125 1350)(-3125 1300);
WIRE 16 -1 (-3400 1300)(-3125 1300);
WIRE 16 -1 (-3125 1400)(-3125 1350);
WIRE 16 -1 (-3400 1350)(-3125 1350);
WIRE 16 -1 (-3125 1400)(-3125 1450);
WIRE 16 -1 (-3400 1400)(-3125 1400);
WIRE 16 -1 (-3125 1450)(-3125 1500);
WIRE 16 -1 (-3400 1450)(-3125 1450);
WIRE 16 -1 (-3125 1500)(-3125 1550);
WIRE 16 -1 (-3400 1500)(-3125 1500);
WIRE 16 -1 (-3125 1550)(-3125 1600);
WIRE 16 -1 (-3400 1550)(-3125 1550);
WIRE 16 -1 (-3125 1600)(-3125 1650);
WIRE 16 -1 (-3400 1600)(-3125 1600);
WIRE 16 -1 (-3125 1650)(-3125 1700);
WIRE 16 -1 (-3400 1650)(-3125 1650);
WIRE 16 -1 (-3125 1700)(-3125 1750);
WIRE 16 -1 (-3400 1700)(-3125 1700);
WIRE 16 -1 (-3125 1750)(-3125 1800);
WIRE 16 -1 (-3400 1750)(-3125 1750);
WIRE 16 -1 (-3125 1800)(-3125 1850);
WIRE 16 -1 (-3400 1800)(-3125 1800);
WIRE 16 -1 (-3125 1850)(-3125 1900);
WIRE 16 -1 (-3400 1850)(-3125 1850);
WIRE 16 -1 (-3125 1900)(-3125 1950);
WIRE 16 -1 (-3400 1900)(-3125 1900);
WIRE 16 -1 (-3125 1950)(-3125 2000);
WIRE 16 -1 (-3400 1950)(-3125 1950);
WIRE 16 -1 (-3125 2000)(-3125 2050);
WIRE 16 -1 (-3400 2000)(-3125 2000);
WIRE 16 -1 (-3125 2050)(-3125 2100);
WIRE 16 -1 (-3400 2050)(-3125 2050);
WIRE 16 -1 (-3125 2100)(-3125 2150);
WIRE 16 -1 (-3400 2100)(-3125 2100);
WIRE 16 -1 (-3125 2150)(-3125 2200);
WIRE 16 -1 (-3400 2150)(-3125 2150);
WIRE 16 -1 (-3125 2200)(-3125 2250);
WIRE 16 -1 (-3400 2200)(-3125 2200);
WIRE 16 -1 (-3125 2250)(-3125 2300);
WIRE 16 -1 (-3400 2250)(-3125 2250);
WIRE 16 -1 (-3125 2300)(-3125 2350);
WIRE 16 -1 (-3400 2300)(-3125 2300);
WIRE 16 -1 (-3125 2350)(-3125 2400);
WIRE 16 -1 (-3400 2350)(-3125 2350);
WIRE 16 -1 (-3125 2400)(-3125 2450);
WIRE 16 -1 (-3400 2400)(-3125 2400);
WIRE 16 -1 (-3125 2450)(-3125 2500);
WIRE 16 -1 (-3400 2450)(-3125 2450);
WIRE 16 -1 (-3125 2500)(-3125 2550);
WIRE 16 -1 (-3400 2500)(-3125 2500);
WIRE 16 -1 (-3125 2550)(-3125 2600);
WIRE 16 -1 (-3400 2550)(-3125 2550);
WIRE 16 -1 (-3125 2600)(-3125 2650);
WIRE 16 -1 (-3400 2600)(-3125 2600);
WIRE 16 -1 (-3125 2650)(-3125 2700);
WIRE 16 -1 (-3400 2650)(-3125 2650);
WIRE 16 -1 (-3125 2700)(-3125 2750);
WIRE 16 -1 (-3400 2700)(-3125 2700);
WIRE 16 -1 (-3125 2750)(-3125 2800);
WIRE 16 -1 (-3400 2750)(-3125 2750);
WIRE 16 -1 (-3125 2800)(-3125 2850);
WIRE 16 -1 (-3400 2800)(-3125 2800);
WIRE 16 -1 (-3125 2850)(-3125 2900);
WIRE 16 -1 (-3400 2850)(-3125 2850);
WIRE 16 -1 (-3125 2900)(-3125 2950);
WIRE 16 -1 (-3400 2900)(-3125 2900);
WIRE 16 -1 (-3125 2950)(-3125 3000);
WIRE 16 -1 (-3400 2950)(-3125 2950);
WIRE 16 -1 (-3125 3000)(-3125 3050);
WIRE 16 -1 (-3400 3000)(-3125 3000);
WIRE 16 -1 (-3125 3050)(-3125 3100);
WIRE 16 -1 (-3400 3050)(-3125 3050);
WIRE 16 -1 (-3125 3100)(-3125 3150);
WIRE 16 -1 (-3400 3100)(-3125 3100);
WIRE 16 -1 (-3125 3150)(-3125 3200);
WIRE 16 -1 (-3400 3150)(-3125 3150);
WIRE 16 -1 (-3125 3200)(-3125 3250);
WIRE 16 -1 (-3400 3200)(-3125 3200);
WIRE 16 -1 (-3125 3250)(-3125 3300);
WIRE 16 -1 (-3400 3250)(-3125 3250);
WIRE 16 -1 (-3125 3300)(-3125 3350);
WIRE 16 -1 (-3400 3300)(-3125 3300);
WIRE 16 -1 (-3125 3350)(-3125 3400);
WIRE 16 -1 (-3400 3350)(-3125 3350);
WIRE 16 -1 (-3125 3400)(-3125 3450);
WIRE 16 -1 (-3400 3400)(-3125 3400);
WIRE 16 -1 (-3125 3450)(-3125 3500);
WIRE 16 -1 (-3400 3450)(-3125 3450);
WIRE 16 -1 (-3125 3500)(-3125 3550);
WIRE 16 -1 (-3400 3500)(-3125 3500);
WIRE 16 -1 (-3125 3550)(-3125 3600);
WIRE 16 -1 (-3400 3550)(-3125 3550);
WIRE 16 -1 (-3125 3600)(-3125 3650);
WIRE 16 -1 (-3400 3600)(-3125 3600);
WIRE 16 -1 (-3125 3650)(-3125 3700);
WIRE 16 -1 (-3400 3650)(-3125 3650);
WIRE 16 -1 (-3125 3700)(-3125 3750);
WIRE 16 -1 (-3400 3700)(-3125 3700);
WIRE 16 -1 (-3125 3750)(-3125 3800);
WIRE 16 -1 (-3400 3750)(-3125 3750);
WIRE 16 -1 (-3125 3800)(-3125 3850);
WIRE 16 -1 (-3400 3800)(-3125 3800);
WIRE 16 -1 (-3125 3850)(-3125 3900);
WIRE 16 -1 (-3400 3850)(-3125 3850);
WIRE 16 -1 (-3125 3900)(-3125 3950);
WIRE 16 -1 (-3400 3900)(-3125 3900);
WIRE 16 -1 (-3125 3950)(-3125 4000);
WIRE 16 -1 (-3400 3950)(-3125 3950);
WIRE 16 -1 (-3125 4000)(-3125 4050);
WIRE 16 -1 (-3400 4000)(-3125 4000);
WIRE 16 -1 (-3125 4050)(-3125 4100);
WIRE 16 -1 (-3400 4050)(-3125 4050);
WIRE 16 -1 (-3125 4100)(-3125 4150);
WIRE 16 -1 (-3400 4100)(-3125 4100);
WIRE 16 -1 (-3125 4150)(-3125 4200);
WIRE 16 -1 (-3400 4150)(-3125 4150);
WIRE 16 -1 (-3125 4200)(-3125 4250);
WIRE 16 -1 (-3400 4200)(-3125 4200);
WIRE 16 -1 (-3125 4250)(-3125 4300);
WIRE 16 -1 (-3400 4250)(-3125 4250);
WIRE 16 -1 (-3125 4300)(-3125 4350);
WIRE 16 -1 (-3400 4300)(-3125 4300);
WIRE 16 -1 (-3125 4350)(-3125 4400);
WIRE 16 -1 (-3400 4350)(-3125 4350);
WIRE 16 -1 (-3125 4400)(-3400 4400);
WIRE 16 -1 (-4950 650)(-4950 950);
WIRE 16 -1 (-4950 1000)(-4950 950);
WIRE 16 -1 (-4950 950)(-4600 950);
WIRE 16 -1 (-4950 1050)(-4950 1000);
WIRE 16 -1 (-4950 1000)(-4600 1000);
WIRE 16 -1 (-4950 1100)(-4950 1050);
WIRE 16 -1 (-4600 1050)(-4950 1050);
WIRE 16 -1 (-4950 1150)(-4950 1100);
WIRE 16 -1 (-4600 1100)(-4950 1100);
WIRE 16 -1 (-4950 1200)(-4950 1150);
WIRE 16 -1 (-4600 1150)(-4950 1150);
WIRE 16 -1 (-4950 1250)(-4950 1200);
WIRE 16 -1 (-4600 1200)(-4950 1200);
WIRE 16 -1 (-4950 1300)(-4950 1250);
WIRE 16 -1 (-4600 1250)(-4950 1250);
WIRE 16 -1 (-4950 1350)(-4950 1300);
WIRE 16 -1 (-4600 1300)(-4950 1300);
WIRE 16 -1 (-4950 1400)(-4950 1350);
WIRE 16 -1 (-4600 1350)(-4950 1350);
WIRE 16 -1 (-4950 1450)(-4950 1400);
WIRE 16 -1 (-4600 1400)(-4950 1400);
WIRE 16 -1 (-4950 1500)(-4950 1450);
WIRE 16 -1 (-4600 1450)(-4950 1450);
WIRE 16 -1 (-4950 1550)(-4950 1500);
WIRE 16 -1 (-4600 1500)(-4950 1500);
WIRE 16 -1 (-4950 1600)(-4950 1550);
WIRE 16 -1 (-4600 1550)(-4950 1550);
WIRE 16 -1 (-4950 1650)(-4950 1600);
WIRE 16 -1 (-4600 1600)(-4950 1600);
WIRE 16 -1 (-4950 1700)(-4950 1650);
WIRE 16 -1 (-4600 1650)(-4950 1650);
WIRE 16 -1 (-4950 1750)(-4950 1700);
WIRE 16 -1 (-4600 1700)(-4950 1700);
WIRE 16 -1 (-4950 1800)(-4950 1750);
WIRE 16 -1 (-4600 1750)(-4950 1750);
WIRE 16 -1 (-4950 1850)(-4950 1800);
WIRE 16 -1 (-4600 1800)(-4950 1800);
WIRE 16 -1 (-4950 1900)(-4950 1850);
WIRE 16 -1 (-4600 1850)(-4950 1850);
WIRE 16 -1 (-4950 1950)(-4950 1900);
WIRE 16 -1 (-4600 1900)(-4950 1900);
WIRE 16 -1 (-4950 2000)(-4950 1950);
WIRE 16 -1 (-4600 1950)(-4950 1950);
WIRE 16 -1 (-4950 2050)(-4950 2000);
WIRE 16 -1 (-4600 2000)(-4950 2000);
WIRE 16 -1 (-4950 2100)(-4950 2050);
WIRE 16 -1 (-4600 2050)(-4950 2050);
WIRE 16 -1 (-4950 2150)(-4950 2100);
WIRE 16 -1 (-4600 2100)(-4950 2100);
WIRE 16 -1 (-4950 2200)(-4950 2150);
WIRE 16 -1 (-4600 2150)(-4950 2150);
WIRE 16 -1 (-4950 2250)(-4950 2200);
WIRE 16 -1 (-4600 2200)(-4950 2200);
WIRE 16 -1 (-4950 2300)(-4950 2250);
WIRE 16 -1 (-4600 2250)(-4950 2250);
WIRE 16 -1 (-4950 2350)(-4950 2300);
WIRE 16 -1 (-4600 2300)(-4950 2300);
WIRE 16 -1 (-4950 2400)(-4950 2350);
WIRE 16 -1 (-4600 2350)(-4950 2350);
WIRE 16 -1 (-4950 2450)(-4950 2400);
WIRE 16 -1 (-4600 2400)(-4950 2400);
WIRE 16 -1 (-4950 2500)(-4950 2450);
WIRE 16 -1 (-4600 2450)(-4950 2450);
WIRE 16 -1 (-4950 2550)(-4950 2500);
WIRE 16 -1 (-4600 2500)(-4950 2500);
WIRE 16 -1 (-4950 2600)(-4950 2550);
WIRE 16 -1 (-4600 2550)(-4950 2550);
WIRE 16 -1 (-4950 2650)(-4950 2600);
WIRE 16 -1 (-4600 2600)(-4950 2600);
WIRE 16 -1 (-4950 2700)(-4950 2650);
WIRE 16 -1 (-4600 2650)(-4950 2650);
WIRE 16 -1 (-4950 2750)(-4950 2700);
WIRE 16 -1 (-4600 2700)(-4950 2700);
WIRE 16 -1 (-4950 2800)(-4950 2750);
WIRE 16 -1 (-4600 2750)(-4950 2750);
WIRE 16 -1 (-4950 2850)(-4950 2800);
WIRE 16 -1 (-4600 2800)(-4950 2800);
WIRE 16 -1 (-4950 2900)(-4950 2850);
WIRE 16 -1 (-4600 2850)(-4950 2850);
WIRE 16 -1 (-4950 2950)(-4950 2900);
WIRE 16 -1 (-4600 2900)(-4950 2900);
WIRE 16 -1 (-4950 3000)(-4950 2950);
WIRE 16 -1 (-4600 2950)(-4950 2950);
WIRE 16 -1 (-4950 3050)(-4950 3000);
WIRE 16 -1 (-4600 3000)(-4950 3000);
WIRE 16 -1 (-4950 3100)(-4950 3050);
WIRE 16 -1 (-4600 3050)(-4950 3050);
WIRE 16 -1 (-4950 3150)(-4950 3100);
WIRE 16 -1 (-4600 3100)(-4950 3100);
WIRE 16 -1 (-4950 3200)(-4950 3150);
WIRE 16 -1 (-4600 3150)(-4950 3150);
WIRE 16 -1 (-4950 3250)(-4950 3200);
WIRE 16 -1 (-4600 3200)(-4950 3200);
WIRE 16 -1 (-4950 3300)(-4950 3250);
WIRE 16 -1 (-4600 3250)(-4950 3250);
WIRE 16 -1 (-4950 3350)(-4950 3300);
WIRE 16 -1 (-4600 3300)(-4950 3300);
WIRE 16 -1 (-4950 3400)(-4950 3350);
WIRE 16 -1 (-4600 3350)(-4950 3350);
WIRE 16 -1 (-4950 3450)(-4950 3400);
WIRE 16 -1 (-4600 3400)(-4950 3400);
WIRE 16 -1 (-4950 3500)(-4950 3450);
WIRE 16 -1 (-4600 3450)(-4950 3450);
WIRE 16 -1 (-4950 3550)(-4950 3500);
WIRE 16 -1 (-4600 3500)(-4950 3500);
WIRE 16 -1 (-4950 3600)(-4950 3550);
WIRE 16 -1 (-4600 3550)(-4950 3550);
WIRE 16 -1 (-4950 3650)(-4950 3600);
WIRE 16 -1 (-4600 3600)(-4950 3600);
WIRE 16 -1 (-4950 3700)(-4950 3650);
WIRE 16 -1 (-4600 3650)(-4950 3650);
WIRE 16 -1 (-4950 3750)(-4950 3700);
WIRE 16 -1 (-4600 3700)(-4950 3700);
WIRE 16 -1 (-4950 3800)(-4950 3750);
WIRE 16 -1 (-4600 3750)(-4950 3750);
WIRE 16 -1 (-4950 3850)(-4950 3800);
WIRE 16 -1 (-4600 3800)(-4950 3800);
WIRE 16 -1 (-4950 3900)(-4950 3850);
WIRE 16 -1 (-4600 3850)(-4950 3850);
WIRE 16 -1 (-4950 3950)(-4950 3900);
WIRE 16 -1 (-4600 3900)(-4950 3900);
WIRE 16 -1 (-4950 4000)(-4950 3950);
WIRE 16 -1 (-4600 3950)(-4950 3950);
WIRE 16 -1 (-4950 4050)(-4950 4000);
WIRE 16 -1 (-4600 4000)(-4950 4000);
WIRE 16 -1 (-4950 4100)(-4950 4050);
WIRE 16 -1 (-4600 4050)(-4950 4050);
WIRE 16 -1 (-4950 4150)(-4950 4100);
WIRE 16 -1 (-4600 4100)(-4950 4100);
WIRE 16 -1 (-4950 4150)(-4950 4200);
WIRE 16 -1 (-4600 4150)(-4950 4150);
WIRE 16 -1 (-4950 4200)(-4950 4250);
WIRE 16 -1 (-4600 4200)(-4950 4200);
WIRE 16 -1 (-4950 4250)(-4950 4300);
WIRE 16 -1 (-4600 4250)(-4950 4250);
WIRE 16 -1 (-4950 4300)(-4950 4350);
WIRE 16 -1 (-4600 4300)(-4950 4300);
WIRE 16 -1 (-4950 4350)(-4950 4400);
WIRE 16 -1 (-4600 4350)(-4950 4350);
WIRE 16 -1 (-4950 4400)(-4600 4400);
WIRE 16 -1 (-400 625)(-400 975);
WIRE 16 -1 (-400 1025)(-400 975);
WIRE 16 -1 (-875 975)(-400 975);
WIRE 16 -1 (-400 1075)(-400 1025);
WIRE 16 -1 (-875 1025)(-400 1025);
WIRE 16 -1 (-400 1125)(-400 1075);
WIRE 16 -1 (-875 1075)(-400 1075);
WIRE 16 -1 (-400 1175)(-400 1125);
WIRE 16 -1 (-875 1125)(-400 1125);
WIRE 16 -1 (-400 1225)(-400 1175);
WIRE 16 -1 (-875 1175)(-400 1175);
WIRE 16 -1 (-400 1275)(-400 1225);
WIRE 16 -1 (-875 1225)(-400 1225);
WIRE 16 -1 (-400 1325)(-400 1275);
WIRE 16 -1 (-875 1275)(-400 1275);
WIRE 16 -1 (-400 1375)(-400 1325);
WIRE 16 -1 (-875 1325)(-400 1325);
WIRE 16 -1 (-400 1425)(-400 1375);
WIRE 16 -1 (-875 1375)(-400 1375);
WIRE 16 -1 (-400 1475)(-400 1425);
WIRE 16 -1 (-875 1425)(-400 1425);
WIRE 16 -1 (-400 1525)(-400 1475);
WIRE 16 -1 (-875 1475)(-400 1475);
WIRE 16 -1 (-400 1575)(-400 1525);
WIRE 16 -1 (-875 1525)(-400 1525);
WIRE 16 -1 (-400 1625)(-400 1575);
WIRE 16 -1 (-875 1575)(-400 1575);
WIRE 16 -1 (-400 1675)(-400 1625);
WIRE 16 -1 (-875 1625)(-400 1625);
WIRE 16 -1 (-400 1725)(-400 1675);
WIRE 16 -1 (-875 1675)(-400 1675);
WIRE 16 -1 (-400 1775)(-400 1725);
WIRE 16 -1 (-875 1725)(-400 1725);
WIRE 16 -1 (-400 1825)(-400 1775);
WIRE 16 -1 (-875 1775)(-400 1775);
WIRE 16 -1 (-400 1875)(-400 1825);
WIRE 16 -1 (-875 1825)(-400 1825);
WIRE 16 -1 (-400 1925)(-400 1875);
WIRE 16 -1 (-875 1875)(-400 1875);
WIRE 16 -1 (-400 1925)(-400 1975);
WIRE 16 -1 (-875 1925)(-400 1925);
WIRE 16 -1 (-400 2025)(-400 1975);
WIRE 16 -1 (-875 1975)(-400 1975);
WIRE 16 -1 (-400 2075)(-400 2025);
WIRE 16 -1 (-875 2025)(-400 2025);
WIRE 16 -1 (-400 2125)(-400 2075);
WIRE 16 -1 (-875 2075)(-400 2075);
WIRE 16 -1 (-400 2175)(-400 2125);
WIRE 16 -1 (-875 2125)(-400 2125);
WIRE 16 -1 (-400 2225)(-400 2175);
WIRE 16 -1 (-875 2175)(-400 2175);
WIRE 16 -1 (-400 2275)(-400 2225);
WIRE 16 -1 (-875 2225)(-400 2225);
WIRE 16 -1 (-400 2325)(-400 2275);
WIRE 16 -1 (-875 2275)(-400 2275);
WIRE 16 -1 (-400 2375)(-400 2325);
WIRE 16 -1 (-875 2325)(-400 2325);
WIRE 16 -1 (-400 2425)(-400 2375);
WIRE 16 -1 (-875 2375)(-400 2375);
WIRE 16 -1 (-400 2475)(-400 2425);
WIRE 16 -1 (-875 2425)(-400 2425);
WIRE 16 -1 (-400 2525)(-400 2475);
WIRE 16 -1 (-875 2475)(-400 2475);
WIRE 16 -1 (-400 2575)(-400 2525);
WIRE 16 -1 (-875 2525)(-400 2525);
WIRE 16 -1 (-400 2625)(-400 2575);
WIRE 16 -1 (-875 2575)(-400 2575);
WIRE 16 -1 (-400 2675)(-400 2625);
WIRE 16 -1 (-875 2625)(-400 2625);
WIRE 16 -1 (-400 2725)(-400 2675);
WIRE 16 -1 (-875 2675)(-400 2675);
WIRE 16 -1 (-400 2775)(-400 2725);
WIRE 16 -1 (-875 2725)(-400 2725);
WIRE 16 -1 (-400 2825)(-400 2775);
WIRE 16 -1 (-875 2775)(-400 2775);
WIRE 16 -1 (-400 2875)(-400 2825);
WIRE 16 -1 (-875 2825)(-400 2825);
WIRE 16 -1 (-400 2875)(-400 2925);
WIRE 16 -1 (-875 2875)(-400 2875);
WIRE 16 -1 (-400 2925)(-400 2975);
WIRE 16 -1 (-875 2925)(-400 2925);
WIRE 16 -1 (-400 2975)(-400 3025);
WIRE 16 -1 (-875 2975)(-400 2975);
WIRE 16 -1 (-400 3025)(-400 3075);
WIRE 16 -1 (-875 3025)(-400 3025);
WIRE 16 -1 (-400 3075)(-400 3125);
WIRE 16 -1 (-875 3075)(-400 3075);
WIRE 16 -1 (-400 3125)(-400 3175);
WIRE 16 -1 (-875 3125)(-400 3125);
WIRE 16 -1 (-400 3175)(-400 3225);
WIRE 16 -1 (-875 3175)(-400 3175);
WIRE 16 -1 (-400 3225)(-400 3275);
WIRE 16 -1 (-875 3225)(-400 3225);
WIRE 16 -1 (-400 3275)(-400 3325);
WIRE 16 -1 (-875 3275)(-400 3275);
WIRE 16 -1 (-400 3325)(-400 3375);
WIRE 16 -1 (-875 3325)(-400 3325);
WIRE 16 -1 (-400 3375)(-400 3425);
WIRE 16 -1 (-875 3375)(-400 3375);
WIRE 16 -1 (-400 3425)(-400 3475);
WIRE 16 -1 (-875 3425)(-400 3425);
WIRE 16 -1 (-400 3475)(-400 3525);
WIRE 16 -1 (-875 3475)(-400 3475);
WIRE 16 -1 (-400 3525)(-400 3575);
WIRE 16 -1 (-875 3525)(-400 3525);
WIRE 16 -1 (-400 3575)(-400 3625);
WIRE 16 -1 (-875 3575)(-400 3575);
WIRE 16 -1 (-400 3625)(-400 3675);
WIRE 16 -1 (-875 3625)(-400 3625);
WIRE 16 -1 (-400 3675)(-400 3725);
WIRE 16 -1 (-875 3675)(-400 3675);
WIRE 16 -1 (-400 3725)(-400 3775);
WIRE 16 -1 (-875 3725)(-400 3725);
WIRE 16 -1 (-400 3775)(-400 3825);
WIRE 16 -1 (-875 3775)(-400 3775);
WIRE 16 -1 (-400 3825)(-400 3875);
WIRE 16 -1 (-875 3825)(-400 3825);
WIRE 16 -1 (-400 3875)(-400 3925);
WIRE 16 -1 (-875 3875)(-400 3875);
WIRE 16 -1 (-400 3925)(-400 3975);
WIRE 16 -1 (-875 3925)(-400 3925);
WIRE 16 -1 (-400 3975)(-400 4025);
WIRE 16 -1 (-875 3975)(-400 3975);
WIRE 16 -1 (-400 4025)(-400 4075);
WIRE 16 -1 (-875 4025)(-400 4025);
WIRE 16 -1 (-400 4075)(-400 4125);
WIRE 16 -1 (-875 4075)(-400 4075);
WIRE 16 -1 (-400 4125)(-400 4175);
WIRE 16 -1 (-875 4125)(-400 4125);
WIRE 16 -1 (-400 4175)(-400 4225);
WIRE 16 -1 (-875 4175)(-400 4175);
WIRE 16 -1 (-400 4225)(-400 4275);
WIRE 16 -1 (-875 4225)(-400 4225);
WIRE 16 -1 (-400 4275)(-400 4325);
WIRE 16 -1 (-875 4275)(-400 4275);
WIRE 16 -1 (-400 4325)(-400 4375);
WIRE 16 -1 (-875 4325)(-400 4325);
WIRE 16 -1 (-400 4375)(-400 4425);
WIRE 16 -1 (-875 4375)(-400 4375);
WIRE 16 -1 (-400 4425)(-875 4425);
WIRE 16 -1 (-2550 675)(-2550 975);
WIRE 16 -1 (-2550 1025)(-2550 975);
WIRE 16 -1 (-2550 975)(-2075 975);
WIRE 16 -1 (-2550 1075)(-2550 1025);
WIRE 16 -1 (-2550 1025)(-2075 1025);
WIRE 16 -1 (-2550 1125)(-2550 1075);
WIRE 16 -1 (-2075 1075)(-2550 1075);
WIRE 16 -1 (-2550 1175)(-2550 1125);
WIRE 16 -1 (-2075 1125)(-2550 1125);
WIRE 16 -1 (-2550 1225)(-2550 1175);
WIRE 16 -1 (-2075 1175)(-2550 1175);
WIRE 16 -1 (-2550 1275)(-2550 1225);
WIRE 16 -1 (-2075 1225)(-2550 1225);
WIRE 16 -1 (-2550 1325)(-2550 1275);
WIRE 16 -1 (-2075 1275)(-2550 1275);
WIRE 16 -1 (-2550 1375)(-2550 1325);
WIRE 16 -1 (-2075 1325)(-2550 1325);
WIRE 16 -1 (-2550 1425)(-2550 1375);
WIRE 16 -1 (-2075 1375)(-2550 1375);
WIRE 16 -1 (-2550 1475)(-2550 1425);
WIRE 16 -1 (-2075 1425)(-2550 1425);
WIRE 16 -1 (-2550 1525)(-2550 1475);
WIRE 16 -1 (-2075 1475)(-2550 1475);
WIRE 16 -1 (-2550 1575)(-2550 1525);
WIRE 16 -1 (-2075 1525)(-2550 1525);
WIRE 16 -1 (-2550 1625)(-2550 1575);
WIRE 16 -1 (-2075 1575)(-2550 1575);
WIRE 16 -1 (-2550 1675)(-2550 1625);
WIRE 16 -1 (-2075 1625)(-2550 1625);
WIRE 16 -1 (-2550 1725)(-2550 1675);
WIRE 16 -1 (-2075 1675)(-2550 1675);
WIRE 16 -1 (-2550 1775)(-2550 1725);
WIRE 16 -1 (-2075 1725)(-2550 1725);
WIRE 16 -1 (-2550 1825)(-2550 1775);
WIRE 16 -1 (-2075 1775)(-2550 1775);
WIRE 16 -1 (-2550 1875)(-2550 1825);
WIRE 16 -1 (-2075 1825)(-2550 1825);
WIRE 16 -1 (-2550 1925)(-2550 1875);
WIRE 16 -1 (-2075 1875)(-2550 1875);
WIRE 16 -1 (-2550 1975)(-2550 1925);
WIRE 16 -1 (-2075 1925)(-2550 1925);
WIRE 16 -1 (-2550 2025)(-2550 1975);
WIRE 16 -1 (-2075 1975)(-2550 1975);
WIRE 16 -1 (-2550 2075)(-2550 2025);
WIRE 16 -1 (-2075 2025)(-2550 2025);
WIRE 16 -1 (-2550 2125)(-2550 2075);
WIRE 16 -1 (-2075 2075)(-2550 2075);
WIRE 16 -1 (-2550 2175)(-2550 2125);
WIRE 16 -1 (-2075 2125)(-2550 2125);
WIRE 16 -1 (-2550 2225)(-2550 2175);
WIRE 16 -1 (-2075 2175)(-2550 2175);
WIRE 16 -1 (-2550 2275)(-2550 2225);
WIRE 16 -1 (-2075 2225)(-2550 2225);
WIRE 16 -1 (-2550 2325)(-2550 2275);
WIRE 16 -1 (-2075 2275)(-2550 2275);
WIRE 16 -1 (-2550 2375)(-2550 2325);
WIRE 16 -1 (-2075 2325)(-2550 2325);
WIRE 16 -1 (-2550 2425)(-2550 2375);
WIRE 16 -1 (-2075 2375)(-2550 2375);
WIRE 16 -1 (-2550 2475)(-2550 2425);
WIRE 16 -1 (-2075 2425)(-2550 2425);
WIRE 16 -1 (-2550 2525)(-2550 2475);
WIRE 16 -1 (-2075 2475)(-2550 2475);
WIRE 16 -1 (-2550 2575)(-2550 2525);
WIRE 16 -1 (-2075 2525)(-2550 2525);
WIRE 16 -1 (-2550 2625)(-2550 2575);
WIRE 16 -1 (-2075 2575)(-2550 2575);
WIRE 16 -1 (-2550 2675)(-2550 2625);
WIRE 16 -1 (-2075 2625)(-2550 2625);
WIRE 16 -1 (-2550 2725)(-2550 2675);
WIRE 16 -1 (-2075 2675)(-2550 2675);
WIRE 16 -1 (-2550 2775)(-2550 2725);
WIRE 16 -1 (-2075 2725)(-2550 2725);
WIRE 16 -1 (-2550 2825)(-2550 2775);
WIRE 16 -1 (-2075 2775)(-2550 2775);
WIRE 16 -1 (-2550 2875)(-2550 2825);
WIRE 16 -1 (-2075 2825)(-2550 2825);
WIRE 16 -1 (-2550 2925)(-2550 2875);
WIRE 16 -1 (-2075 2875)(-2550 2875);
WIRE 16 -1 (-2550 2975)(-2550 2925);
WIRE 16 -1 (-2075 2925)(-2550 2925);
WIRE 16 -1 (-2550 3025)(-2550 2975);
WIRE 16 -1 (-2075 2975)(-2550 2975);
WIRE 16 -1 (-2550 3075)(-2550 3025);
WIRE 16 -1 (-2075 3025)(-2550 3025);
WIRE 16 -1 (-2550 3125)(-2550 3075);
WIRE 16 -1 (-2075 3075)(-2550 3075);
WIRE 16 -1 (-2550 3175)(-2550 3125);
WIRE 16 -1 (-2075 3125)(-2550 3125);
WIRE 16 -1 (-2550 3225)(-2550 3175);
WIRE 16 -1 (-2075 3175)(-2550 3175);
WIRE 16 -1 (-2550 3275)(-2550 3225);
WIRE 16 -1 (-2075 3225)(-2550 3225);
WIRE 16 -1 (-2550 3325)(-2550 3275);
WIRE 16 -1 (-2075 3275)(-2550 3275);
WIRE 16 -1 (-2550 3375)(-2550 3325);
WIRE 16 -1 (-2075 3325)(-2550 3325);
WIRE 16 -1 (-2550 3425)(-2550 3375);
WIRE 16 -1 (-2075 3375)(-2550 3375);
WIRE 16 -1 (-2550 3475)(-2550 3425);
WIRE 16 -1 (-2075 3425)(-2550 3425);
WIRE 16 -1 (-2550 3525)(-2550 3475);
WIRE 16 -1 (-2075 3475)(-2550 3475);
WIRE 16 -1 (-2550 3575)(-2550 3525);
WIRE 16 -1 (-2075 3525)(-2550 3525);
WIRE 16 -1 (-2550 3625)(-2550 3575);
WIRE 16 -1 (-2075 3575)(-2550 3575);
WIRE 16 -1 (-2550 3675)(-2550 3625);
WIRE 16 -1 (-2075 3625)(-2550 3625);
WIRE 16 -1 (-2550 3725)(-2550 3675);
WIRE 16 -1 (-2075 3675)(-2550 3675);
WIRE 16 -1 (-2550 3775)(-2550 3725);
WIRE 16 -1 (-2075 3725)(-2550 3725);
WIRE 16 -1 (-2550 3825)(-2550 3775);
WIRE 16 -1 (-2075 3775)(-2550 3775);
WIRE 16 -1 (-2550 3875)(-2550 3825);
WIRE 16 -1 (-2075 3825)(-2550 3825);
WIRE 16 -1 (-2550 3925)(-2550 3875);
WIRE 16 -1 (-2075 3875)(-2550 3875);
WIRE 16 -1 (-2550 3975)(-2550 3925);
WIRE 16 -1 (-2075 3925)(-2550 3925);
WIRE 16 -1 (-2550 4025)(-2550 3975);
WIRE 16 -1 (-2075 3975)(-2550 3975);
WIRE 16 -1 (-2550 4075)(-2550 4025);
WIRE 16 -1 (-2075 4025)(-2550 4025);
WIRE 16 -1 (-2550 4125)(-2550 4075);
WIRE 16 -1 (-2075 4075)(-2550 4075);
WIRE 16 -1 (-2550 4175)(-2550 4125);
WIRE 16 -1 (-2075 4125)(-2550 4125);
WIRE 16 -1 (-2550 4225)(-2550 4175);
WIRE 16 -1 (-2075 4175)(-2550 4175);
WIRE 16 -1 (-2550 4275)(-2550 4225);
WIRE 16 -1 (-2075 4225)(-2550 4225);
WIRE 16 -1 (-2550 4325)(-2550 4275);
WIRE 16 -1 (-2075 4275)(-2550 4275);
WIRE 16 -1 (-2550 4375)(-2550 4325);
WIRE 16 -1 (-2075 4325)(-2550 4325);
WIRE 16 -1 (-2550 4375)(-2550 4425);
WIRE 16 -1 (-2075 4375)(-2550 4375);
WIRE 16 -1 (-2550 4425)(-2075 4425);
DOT 1 (-3125 3500);
DOT 1 (-3125 1900);
DOT 1 (-4950 1250);
DOT 1 (-4950 1000);
DOT 1 (-4950 3750);
DOT 1 (-2550 1825);
DOT 1 (-2550 1725);
DOT 1 (-4950 2050);
DOT 1 (-2550 1875);
DOT 1 (-400 2775);
DOT 1 (-400 2675);
DOT 1 (-400 2625);
DOT 1 (-400 2525);
DOT 1 (-400 2475);
DOT 1 (-400 2425);
DOT 1 (-400 2275);
DOT 1 (-400 2225);
DOT 1 (-400 2075);
DOT 1 (-400 2025);
DOT 1 (-400 1975);
DOT 1 (-400 1825);
DOT 1 (-400 1775);
DOT 1 (-400 1725);
DOT 1 (-400 1675);
DOT 1 (225 1500);
DOT 1 (2200 4200);
DOT 1 (2200 4250);
DOT 1 (-4950 2950);
DOT 1 (-2550 2675);
DOT 1 (-3125 2300);
DOT 1 (-3125 2550);
DOT 1 (-400 2325);
DOT 1 (225 2750);
DOT 1 (2200 4300);
DOT 1 (2200 4350);
DOT 1 (225 4350);
DOT 1 (225 4250);
DOT 1 (225 4300);
DOT 1 (225 4200);
DOT 1 (225 4150);
DOT 1 (225 4100);
DOT 1 (225 4000);
DOT 1 (225 4050);
DOT 1 (225 3950);
DOT 1 (225 3900);
DOT 1 (225 3850);
DOT 1 (225 3750);
DOT 1 (225 3800);
DOT 1 (225 3700);
DOT 1 (225 3650);
DOT 1 (225 3600);
DOT 1 (225 3500);
DOT 1 (225 3550);
DOT 1 (225 3450);
DOT 1 (225 3400);
DOT 1 (225 3350);
DOT 1 (225 3300);
DOT 1 (225 3250);
DOT 1 (225 3200);
DOT 1 (225 3100);
DOT 1 (225 3050);
DOT 1 (225 3000);
DOT 1 (225 2950);
DOT 1 (225 2850);
DOT 1 (225 2900);
DOT 1 (225 2800);
DOT 1 (225 2700);
DOT 1 (225 2600);
DOT 1 (225 2650);
DOT 1 (225 2550);
DOT 1 (225 2500);
DOT 1 (225 2450);
DOT 1 (225 2350);
DOT 1 (225 2400);
DOT 1 (225 2300);
DOT 1 (225 2250);
DOT 1 (225 2200);
DOT 1 (225 2150);
DOT 1 (225 2100);
DOT 1 (225 2050);
DOT 1 (225 1950);
DOT 1 (225 2000);
DOT 1 (225 1900);
DOT 1 (225 1850);
DOT 1 (225 1800);
DOT 1 (225 1700);
DOT 1 (225 1750);
DOT 1 (225 1650);
DOT 1 (225 1600);
DOT 1 (225 1550);
DOT 1 (225 1450);
DOT 1 (225 1400);
DOT 1 (225 1350);
DOT 1 (225 1300);
DOT 1 (225 1250);
DOT 1 (225 1200);
DOT 1 (225 1150);
DOT 1 (225 1050);
DOT 1 (225 1100);
DOT 1 (225 1000);
DOT 1 (225 950);
DOT 1 (225 3150);
DOT 1 (-400 4375);
DOT 1 (-400 4175);
DOT 1 (-400 4225);
DOT 1 (-400 4275);
DOT 1 (-400 4325);
DOT 1 (-400 4075);
DOT 1 (-400 3925);
DOT 1 (-400 3975);
DOT 1 (-400 4025);
DOT 1 (-400 4125);
DOT 1 (-400 3875);
DOT 1 (-400 3675);
DOT 1 (-400 3725);
DOT 1 (-400 3775);
DOT 1 (-400 3825);
DOT 1 (-400 3625);
DOT 1 (-400 3425);
DOT 1 (-400 3475);
DOT 1 (-400 3525);
DOT 1 (-400 3575);
DOT 1 (-400 3375);
DOT 1 (-400 3175);
DOT 1 (-400 3225);
DOT 1 (-400 3275);
DOT 1 (-400 3325);
DOT 1 (-400 3125);
DOT 1 (-400 2925);
DOT 1 (-400 2975);
DOT 1 (-400 3025);
DOT 1 (-400 3075);
DOT 1 (-400 2875);
DOT 1 (-400 2825);
DOT 1 (-400 2725);
DOT 1 (-400 2575);
DOT 1 (-400 2375);
DOT 1 (-400 2125);
DOT 1 (-400 2175);
DOT 1 (-400 1875);
DOT 1 (-400 1925);
DOT 1 (-400 1625);
DOT 1 (-400 1525);
DOT 1 (-400 1375);
DOT 1 (-400 1425);
DOT 1 (-400 1475);
DOT 1 (-400 1575);
DOT 1 (-400 1325);
DOT 1 (-400 1125);
DOT 1 (-400 1175);
DOT 1 (-400 1225);
DOT 1 (-400 1275);
DOT 1 (-400 1025);
DOT 1 (-400 1075);
DOT 1 (-400 975);
DOT 1 (-2550 4375);
DOT 1 (-2550 4325);
DOT 1 (-2550 4275);
DOT 1 (-2550 4225);
DOT 1 (-2550 4175);
DOT 1 (-2550 4075);
DOT 1 (-2550 4125);
DOT 1 (-2550 4025);
DOT 1 (-2550 3975);
DOT 1 (-2550 3875);
DOT 1 (-2550 3825);
DOT 1 (-2550 3725);
DOT 1 (-2550 3675);
DOT 1 (-2550 3775);
DOT 1 (-2550 3625);
DOT 1 (-2550 3575);
DOT 1 (-2550 3525);
DOT 1 (-2550 3475);
DOT 1 (-2550 3425);
DOT 1 (-2550 3375);
DOT 1 (-2550 3325);
DOT 1 (-2550 3275);
DOT 1 (-2550 3175);
DOT 1 (-2550 3225);
DOT 1 (-2550 3125);
DOT 1 (-2550 3075);
DOT 1 (-2550 3025);
DOT 1 (-2550 2925);
DOT 1 (-2550 2975);
DOT 1 (-2550 2875);
DOT 1 (-2550 2825);
DOT 1 (-2550 2775);
DOT 1 (-2550 2725);
DOT 1 (-2550 2625);
DOT 1 (-2550 2525);
DOT 1 (-2550 2575);
DOT 1 (-2550 2475);
DOT 1 (-2550 2425);
DOT 1 (-2550 2375);
DOT 1 (-2550 2325);
DOT 1 (-2550 2275);
DOT 1 (-2550 2225);
DOT 1 (-2550 2175);
DOT 1 (-2550 2125);
DOT 1 (-2550 2025);
DOT 1 (-2550 2075);
DOT 1 (-2550 1975);
DOT 1 (-2550 1925);
DOT 1 (-2550 1675);
DOT 1 (-2550 1625);
DOT 1 (-2550 1575);
DOT 1 (-2550 1525);
DOT 1 (-2550 1475);
DOT 1 (-2550 1375);
DOT 1 (-2550 1425);
DOT 1 (-2550 1325);
DOT 1 (-2550 1275);
DOT 1 (-2550 1225);
DOT 1 (-2550 1125);
DOT 1 (-2550 1175);
DOT 1 (-2550 1075);
DOT 1 (-2550 1025);
DOT 1 (-2550 975);
DOT 1 (-2550 1775);
DOT 1 (-2550 3925);
DOT 1 (-3125 4350);
DOT 1 (-3125 4300);
DOT 1 (-3125 4200);
DOT 1 (-3125 4250);
DOT 1 (-3125 4150);
DOT 1 (-3125 4100);
DOT 1 (-3125 4050);
DOT 1 (-3125 3950);
DOT 1 (-3125 4000);
DOT 1 (-3125 3900);
DOT 1 (-3125 3850);
DOT 1 (-3125 3800);
DOT 1 (-3125 3700);
DOT 1 (-3125 3750);
DOT 1 (-3125 3650);
DOT 1 (-3125 3600);
DOT 1 (-3125 3550);
DOT 1 (-3125 3450);
DOT 1 (-3125 3350);
DOT 1 (-3125 3400);
DOT 1 (-3125 3300);
DOT 1 (-3125 3250);
DOT 1 (-3125 3200);
DOT 1 (-3125 3150);
DOT 1 (-3125 3050);
DOT 1 (-3125 3100);
DOT 1 (-3125 3000);
DOT 1 (-3125 2950);
DOT 1 (-3125 2900);
DOT 1 (-3125 2800);
DOT 1 (-3125 2850);
DOT 1 (-3125 2750);
DOT 1 (-3125 2700);
DOT 1 (-3125 2650);
DOT 1 (-3125 2600);
DOT 1 (-3125 2500);
DOT 1 (-3125 2450);
DOT 1 (-3125 2400);
DOT 1 (-3125 2350);
DOT 1 (-3125 2250);
DOT 1 (-3125 2200);
DOT 1 (-3125 2150);
DOT 1 (-3125 2100);
DOT 1 (-3125 2050);
DOT 1 (-3125 2000);
DOT 1 (-3125 1950);
DOT 1 (-3125 1850);
DOT 1 (-3125 1750);
DOT 1 (-3125 1800);
DOT 1 (-3125 1650);
DOT 1 (-3125 1700);
DOT 1 (-3125 1600);
DOT 1 (-3125 1550);
DOT 1 (-3125 1500);
DOT 1 (-3125 1400);
DOT 1 (-3125 1450);
DOT 1 (-3125 1350);
DOT 1 (-3125 1300);
DOT 1 (-3125 1250);
DOT 1 (-3125 1200);
DOT 1 (-3125 1150);
DOT 1 (-3125 1100);
DOT 1 (-3125 1000);
DOT 1 (-3125 1050);
DOT 1 (-3125 950);
DOT 1 (-4950 4350);
DOT 1 (-4950 4300);
DOT 1 (-4950 4200);
DOT 1 (-4950 4250);
DOT 1 (-4950 4150);
DOT 1 (-4950 4100);
DOT 1 (-4950 4050);
DOT 1 (-4950 3950);
DOT 1 (-4950 4000);
DOT 1 (-4950 3900);
DOT 1 (-4950 3850);
DOT 1 (-4950 3800);
DOT 1 (-4950 3700);
DOT 1 (-4950 3650);
DOT 1 (-4950 3600);
DOT 1 (-4950 3550);
DOT 1 (-4950 3450);
DOT 1 (-4950 3500);
DOT 1 (-4950 3350);
DOT 1 (-4950 3300);
DOT 1 (-4950 3400);
DOT 1 (-4950 3250);
DOT 1 (-4950 3200);
DOT 1 (-4950 3150);
DOT 1 (-4950 3050);
DOT 1 (-4950 3100);
DOT 1 (-4950 3000);
DOT 1 (-4950 2900);
DOT 1 (-4950 2800);
DOT 1 (-4950 2850);
DOT 1 (-4950 2750);
DOT 1 (-4950 2700);
DOT 1 (-4950 2650);
DOT 1 (-4950 2550);
DOT 1 (-4950 2600);
DOT 1 (-4950 2500);
DOT 1 (-4950 2450);
DOT 1 (-4950 2400);
DOT 1 (-4950 2350);
DOT 1 (-4950 2300);
DOT 1 (-4950 2250);
DOT 1 (-4950 2200);
DOT 1 (-4950 2150);
DOT 1 (-4950 2100);
DOT 1 (-4950 2000);
DOT 1 (-4950 1900);
DOT 1 (-4950 1950);
DOT 1 (-4950 1850);
DOT 1 (-4950 1800);
DOT 1 (-4950 1750);
DOT 1 (-4950 1650);
DOT 1 (-4950 1600);
DOT 1 (-4950 1550);
DOT 1 (-4950 1500);
DOT 1 (-4950 1400);
DOT 1 (-4950 1450);
DOT 1 (-4950 1350);
DOT 1 (-4950 1300);
DOT 1 (-4950 1200);
DOT 1 (-4950 1150);
DOT 1 (-4950 1100);
DOT 1 (-4950 1050);
DOT 1 (-4950 950);
DOT 1 (-4950 1700);
FORCENOTE
ROOM=SB
(-5300 225) 0;
DISPLAY LEFT (-5300 225);
DISPLAY 1.021277 (-5300 225);
PAINT PURPLE (-5300 225);
QUIT
